G04 ================== begin FILE IDENTIFICATION RECORD ==================*
G04 Layout Name:  9052_F0T_PDB_Converter_Brick_F_V03_1208_1600.brd*
G04 Film Name:    vcc1*
G04 File Format:  Gerber RS274X*
G04 File Origin:  Cadence Allegro 17.2-S081*
G04 Origin Date:  Wed Dec 21 09:54:58 2022*
G04 *
G04 Layer:  DRAWING FORMAT/TITLE_BLOCK_A*
G04 Layer:  PIN/SPECIAL_DRILL*
G04 Layer:  DRAWING FORMAT/TITLE_BLOCK*
G04 Layer:  VIA CLASS/VCC1*
G04 Layer:  PIN/VCC1*
G04 Layer:  MANUFACTURING/PHOTOPLOT_OUTLINE*
G04 Layer:  ETCH/VCC1*
G04 Layer:  DRAWING FORMAT/TITLE_DATA_VCC1*
G04 *
G04 Offset:    (0.00 0.00)*
G04 Mirror:    No*
G04 Mode:      Negative*
G04 Rotation:  0*
G04 FullContactRelief:  No*
G04 UndefLineWidth:     6.00*
G04 ================== end FILE IDENTIFICATION RECORD ====================*
%FSLAX25Y25*MOIN*%
%IR0*IPPOS*OFA0.00000B0.00000*MIA0B0*SFA1.00000B1.00000*%
%ADD10C,.03*%
%AMMACRO40*
4,1,41,-.40714,-.11826,
-.427771,-.11755,
-.447965,-.113268,
-.467108,-.105544,
-.48462,-.094614,
-.499967,-.080809,
-.512684,-.064548,
-.522385,-.046326,
-.528773,-.026697,
-.531656,-.006256,
-.530946,.014374,
-.526664,.034568,
-.518941,.053712,
-.50801,.071223,
-.494205,.086571,
-.477944,.099288,
-.459723,.108988,
-.440093,.115377,
-.419653,.11826,
-.40714,.11826,
.33517,.07906,
.45275,.07906,
.466479,.077859,
.47979,.074292,
.49228,.068468,
.503569,.060563,
.513313,.050819,
.521218,.03953,
.527042,.02704,
.530609,.013729,
.53181,0.0,
.530609,-.013729,
.527042,-.02704,
.521218,-.03953,
.513313,-.050819,
.503569,-.060563,
.49228,-.068468,
.47979,-.074292,
.466479,-.077859,
.45275,-.07906,
.33517,-.07906,
-.40714,-.11826,
0.0*
%
%ADD40MACRO40*%
%AMMACRO12*
4,1,41,.45275,-.05906,
.463006,-.058163,
.47295,-.055498,
.48228,-.051147,
.490713,-.045243,
.497993,-.037963,
.503897,-.02953,
.508248,-.0202,
.510913,-.010256,
.51181,0.0,
.510913,.010256,
.508248,.0202,
.503897,.02953,
.497993,.037963,
.490713,.045243,
.48228,.051147,
.47295,.055498,
.463006,.058163,
.45275,.05906,
.33464,.05906,
-.4082,.09829,
-.425347,.097699,
-.442131,.09414,
-.458041,.08772,
-.472595,.078635,
-.485351,.06716,
-.49592,.053645,
-.503981,.0385,
-.509291,.022185,
-.511686,.005196,
-.511095,-.011951,
-.507536,-.028734,
-.501116,-.044645,
-.492031,-.059199,
-.480557,-.071954,
-.467041,-.082523,
-.451896,-.090585,
-.435582,-.095894,
-.418593,-.09829,
-.4082,-.09829,
.33464,-.05906,
.45275,-.05906,
0.0*
%
%ADD12MACRO12*%
%ADD31C,.06*%
%ADD26C,.062*%
%ADD16C,.054*%
%AMMACRO27*
4,1,36,.0025,0.0,
.002462,.000434,
.002349,.000855,
.002165,.00125,
.001915,.001607,
.001607,.001915,
.00125,.002165,
.000855,.002349,
.000434,.002462,
0.0,.0025,
-.000434,.002462,
-.000855,.002349,
-.00125,.002165,
-.001607,.001915,
-.001915,.001607,
-.002165,.00125,
-.002349,.000855,
-.002462,.000434,
-.0025,0.0,
-.002462,-.000434,
-.002349,-.000855,
-.002165,-.00125,
-.001915,-.001607,
-.001607,-.001915,
-.00125,-.002165,
-.000855,-.002349,
-.000434,-.002462,
0.0,-.0025,
.000434,-.002462,
.000855,-.002349,
.00125,-.002165,
.001607,-.001915,
.001915,-.001607,
.002165,-.00125,
.002349,-.000855,
.002462,-.000434,
.0025,0.0,
270.*
%
%ADD27MACRO27*%
%AMMACRO20*
4,1,36,.0025,0.0,
.002462,.000434,
.002349,.000855,
.002165,.00125,
.001915,.001607,
.001607,.001915,
.00125,.002165,
.000855,.002349,
.000434,.002462,
0.0,.0025,
-.000434,.002462,
-.000855,.002349,
-.00125,.002165,
-.001607,.001915,
-.001915,.001607,
-.002165,.00125,
-.002349,.000855,
-.002462,.000434,
-.0025,0.0,
-.002462,-.000434,
-.002349,-.000855,
-.002165,-.00125,
-.001915,-.001607,
-.001607,-.001915,
-.00125,-.002165,
-.000855,-.002349,
-.000434,-.002462,
0.0,-.0025,
.000434,-.002462,
.000855,-.002349,
.00125,-.002165,
.001607,-.001915,
.001915,-.001607,
.002165,-.00125,
.002349,-.000855,
.002462,-.000434,
.0025,0.0,
180.*
%
%ADD20MACRO20*%
%ADD29C,.083*%
%ADD28C,.056*%
%ADD41C,.066*%
%ADD34C,.06015*%
%ADD38C,.087*%
%AMMACRO35*
4,1,36,0.0,.019,
-.003299,.018711,
-.006498,.017854,
-.0095,.016454,
-.012213,.014555,
-.014555,.012213,
-.016454,.0095,
-.017854,.006498,
-.018711,.003299,
-.019,0.0,
-.018711,-.003299,
-.017854,-.006498,
-.016454,-.0095,
-.014555,-.012213,
-.012213,-.014555,
-.0095,-.016454,
-.006498,-.017854,
-.003299,-.018711,
0.0,-.019,
.003299,-.018711,
.006498,-.017854,
.0095,-.016454,
.012213,-.014555,
.014555,-.012213,
.016454,-.0095,
.017854,-.006498,
.018711,-.003299,
.019,0.0,
.018711,.003299,
.017854,.006498,
.016454,.0095,
.014555,.012213,
.012213,.014555,
.0095,.016454,
.006498,.017854,
.003299,.018711,
0.0,.019,
0.0*
%
%ADD35MACRO35*%
%AMMACRO24*
4,1,16,.04271,.02503,
.046408,.017233,
.048695,.008913,
.049503,.000322,
.048807,-.008279,
.046628,-.016629,
.043032,-.024473,
.04271,-.02503,
.0478,-.03012,
.052304,-.021362,
.055219,-.011955,
.056456,-.002185,
.055978,.007652,
.053799,.017256,
.049985,.026336,
.0478,.03012,
.04271,.02503,
270.*
4,1,16,.02503,-.04271,
.017233,-.046408,
.008913,-.048695,
.000322,-.049503,
-.008279,-.048807,
-.016629,-.046628,
-.024473,-.043032,
-.02503,-.04271,
-.03012,-.0478,
-.021362,-.052304,
-.011955,-.055219,
-.002185,-.056456,
.007652,-.055978,
.017256,-.053799,
.026336,-.049985,
.03012,-.0478,
.02503,-.04271,
270.*
4,1,16,-.04271,-.02503,
-.046408,-.017233,
-.048695,-.008913,
-.049503,-.000322,
-.048807,.008279,
-.046628,.016629,
-.043032,.024473,
-.04271,.02503,
-.0478,.03012,
-.052304,.021362,
-.055219,.011955,
-.056456,.002185,
-.055978,-.007652,
-.053799,-.017256,
-.049985,-.026336,
-.0478,-.03012,
-.04271,-.02503,
270.*
4,1,16,-.02503,.04271,
-.017233,.046408,
-.008913,.048695,
-.000322,.049503,
.008279,.048807,
.016629,.046628,
.024473,.043032,
.02503,.04271,
.03012,.0478,
.021362,.052304,
.011955,.055219,
.002185,.056456,
-.007652,.055978,
-.017256,.053799,
-.026336,.049985,
-.03012,.0478,
-.02503,.04271,
270.*
%
%ADD24MACRO24*%
%AMMACRO42*
4,1,16,.02657,.01597,
.02894,.011114,
.03043,.005919,
.030995,.000545,
.030619,-.004845,
.029313,-.010088,
.027115,-.015025,
.02657,-.01597,
.03164,-.02104,
.034813,-.015226,
.036928,-.00895,
.037921,-.002401,
.037762,.00422,
.036455,.010713,
.034041,.016881,
.03164,.02104,
.02657,.01597,
90.*
4,1,16,.01597,-.02657,
.011114,-.02894,
.005919,-.03043,
.000545,-.030995,
-.004845,-.030619,
-.010088,-.029313,
-.015025,-.027115,
-.01597,-.02657,
-.02104,-.03164,
-.015226,-.034813,
-.00895,-.036928,
-.002401,-.037921,
.00422,-.037762,
.010713,-.036455,
.016881,-.034041,
.02104,-.03164,
.01597,-.02657,
90.*
4,1,16,-.02657,-.01597,
-.02894,-.011114,
-.03043,-.005919,
-.030995,-.000545,
-.030619,.004845,
-.029313,.010088,
-.027115,.015025,
-.02657,.01597,
-.03164,.02104,
-.034813,.015226,
-.036928,.00895,
-.037921,.002401,
-.037762,-.00422,
-.036455,-.010713,
-.034041,-.016881,
-.03164,-.02104,
-.02657,-.01597,
90.*
4,1,16,-.01597,.02657,
-.011114,.02894,
-.005919,.03043,
-.000545,.030995,
.004845,.030619,
.010088,.029313,
.015025,.027115,
.01597,.02657,
.02104,.03164,
.015226,.034813,
.00895,.036928,
.002401,.037921,
-.00422,.037762,
-.010713,.036455,
-.016881,.034041,
-.02104,.03164,
-.01597,.02657,
90.*
%
%ADD42MACRO42*%
%AMMACRO25*
4,1,16,.02511,.01451,
.027248,.009929,
.028558,.005047,
.029001,.000011,
.028562,-.005025,
.027256,-.009909,
.025121,-.014491,
.02511,-.01451,
.0302,-.01959,
.033143,-.014048,
.035079,-.00808,
.035949,-.001865,
.035727,.004405,
.034419,.010542,
.032065,.016359,
.0302,.01959,
.02511,.01451,
0.0*
4,1,16,.01451,-.02511,
.009929,-.027248,
.005047,-.028558,
.000011,-.029001,
-.005025,-.028562,
-.009909,-.027256,
-.014491,-.025121,
-.01451,-.02511,
-.01959,-.0302,
-.014048,-.033143,
-.00808,-.035079,
-.001865,-.035949,
.004405,-.035727,
.010542,-.034419,
.016359,-.032065,
.01959,-.0302,
.01451,-.02511,
0.0*
4,1,16,-.02511,-.01451,
-.027248,-.009929,
-.028558,-.005047,
-.029001,-.000011,
-.028562,.005025,
-.027256,.009909,
-.025121,.014491,
-.02511,.01451,
-.0302,.01959,
-.033143,.014048,
-.035079,.00808,
-.035949,.001865,
-.035727,-.004405,
-.034419,-.010542,
-.032065,-.016359,
-.0302,-.01959,
-.02511,-.01451,
0.0*
4,1,16,-.01451,.02511,
-.009929,.027248,
-.005047,.028558,
-.000011,.029001,
.005025,.028562,
.009909,.027256,
.014491,.025121,
.01451,.02511,
.01959,.0302,
.014048,.033143,
.00808,.035079,
.001865,.035949,
-.004405,.035727,
-.010542,.034419,
-.016359,.032065,
-.01959,.0302,
-.01451,.02511,
0.0*
%
%ADD25MACRO25*%
%AMMACRO44*
4,1,15,.03682,.01914,
.039584,.012455,
.041146,.005393,
.041457,-.001834,
.040509,-.009005,
.03833,-.015903,
.03682,-.01914,
.04197,-.0243,
.045552,-.016643,
.04775,-.00848,
.048497,-.000059,
.047771,.008363,
.045593,.016531,
.042029,.024197,
.04197,.0243,
.03682,.01914,
90.*
4,1,15,.01914,-.03682,
.012455,-.039584,
.005393,-.041146,
-.001834,-.041457,
-.009005,-.040509,
-.015903,-.03833,
-.01914,-.03682,
-.0243,-.04197,
-.016643,-.045552,
-.00848,-.04775,
-.000059,-.048497,
.008363,-.047771,
.016531,-.045593,
.024197,-.042029,
.0243,-.04197,
.01914,-.03682,
90.*
4,1,15,-.03682,-.01914,
-.039584,-.012455,
-.041146,-.005393,
-.041457,.001834,
-.040509,.009005,
-.03833,.015903,
-.03682,.01914,
-.04197,.0243,
-.045552,.016643,
-.04775,.00848,
-.048497,.000059,
-.047771,-.008363,
-.045593,-.016531,
-.042029,-.024197,
-.04197,-.0243,
-.03682,-.01914,
90.*
4,1,15,-.01914,.03682,
-.012455,.039584,
-.005393,.041146,
.001834,.041457,
.009005,.040509,
.015903,.03833,
.01914,.03682,
.0243,.04197,
.016643,.045552,
.00848,.04775,
.000059,.048497,
-.008363,.047771,
-.016531,.045593,
-.024197,.042029,
-.0243,.04197,
-.01914,.03682,
90.*
%
%ADD44MACRO44*%
%AMMACRO43*
4,1,15,-.03682,.01914,
-.039584,.012455,
-.041146,.005393,
-.041457,-.001834,
-.040509,-.009005,
-.03833,-.015903,
-.03682,-.01914,
-.04197,-.0243,
-.045552,-.016643,
-.04775,-.00848,
-.048497,-.000059,
-.047771,.008363,
-.045593,.016531,
-.042029,.024197,
-.04197,.0243,
-.03682,.01914,
90.*
4,1,15,-.01914,-.03682,
-.012455,-.039584,
-.005393,-.041146,
.001834,-.041457,
.009005,-.040509,
.015903,-.03833,
.01914,-.03682,
.0243,-.04197,
.016643,-.045552,
.00848,-.04775,
.000059,-.048497,
-.008363,-.047771,
-.016531,-.045593,
-.024197,-.042029,
-.0243,-.04197,
-.01914,-.03682,
90.*
4,1,15,.03682,-.01914,
.039584,-.012455,
.041146,-.005393,
.041457,.001834,
.040509,.009005,
.03833,.015903,
.03682,.01914,
.04197,.0243,
.045552,.016643,
.04775,.00848,
.048497,.000059,
.047771,-.008363,
.045593,-.016531,
.042029,-.024197,
.04197,-.0243,
.03682,-.01914,
90.*
4,1,15,.01914,.03682,
.012455,.039584,
.005393,.041146,
-.001834,.041457,
-.009005,.040509,
-.015903,.03833,
-.01914,.03682,
-.0243,.04197,
-.016643,.045552,
-.00848,.04775,
-.000059,.048497,
.008363,.047771,
.016531,.045593,
.024197,.042029,
.0243,.04197,
.01914,.03682,
90.*
%
%ADD43MACRO43*%
%AMMACRO13*
4,1,36,0.0,.005,
.000868,.004924,
.00171,.004698,
.0025,.00433,
.003214,.00383,
.00383,.003214,
.00433,.0025,
.004698,.00171,
.004924,.000868,
.005,0.0,
.004924,-.000868,
.004698,-.00171,
.00433,-.0025,
.00383,-.003214,
.003214,-.00383,
.0025,-.00433,
.00171,-.004698,
.000868,-.004924,
0.0,-.005,
-.000868,-.004924,
-.00171,-.004698,
-.0025,-.00433,
-.003214,-.00383,
-.00383,-.003214,
-.00433,-.0025,
-.004698,-.00171,
-.004924,-.000868,
-.005,0.0,
-.004924,.000868,
-.004698,.00171,
-.00433,.0025,
-.00383,.003214,
-.003214,.00383,
-.0025,.00433,
-.00171,.004698,
-.000868,.004924,
0.0,.005,
270.*
%
%ADD13MACRO13*%
%ADD11C,.125*%
%ADD14C,.117*%
%ADD22C,.155*%
%ADD19C,.237*%
%ADD30C,.256*%
%AMMACRO23*
4,1,36,.0025,0.0,
.002462,.000434,
.002349,.000855,
.002165,.00125,
.001915,.001607,
.001607,.001915,
.00125,.002165,
.000855,.002349,
.000434,.002462,
0.0,.0025,
-.000434,.002462,
-.000855,.002349,
-.00125,.002165,
-.001607,.001915,
-.001915,.001607,
-.002165,.00125,
-.002349,.000855,
-.002462,.000434,
-.0025,0.0,
-.002462,-.000434,
-.002349,-.000855,
-.002165,-.00125,
-.001915,-.001607,
-.001607,-.001915,
-.00125,-.002165,
-.000855,-.002349,
-.000434,-.002462,
0.0,-.0025,
.000434,-.002462,
.000855,-.002349,
.00125,-.002165,
.001607,-.001915,
.001915,-.001607,
.002165,-.00125,
.002349,-.000855,
.002462,-.000434,
.0025,0.0,
90.*
%
%ADD23MACRO23*%
%ADD18C,.186*%
%ADD46C,.187*%
%AMMACRO36*
4,1,36,0.0,.019,
-.003299,.018711,
-.006498,.017854,
-.0095,.016454,
-.012213,.014555,
-.014555,.012213,
-.016454,.0095,
-.017854,.006498,
-.018711,.003299,
-.019,0.0,
-.018711,-.003299,
-.017854,-.006498,
-.016454,-.0095,
-.014555,-.012213,
-.012213,-.014555,
-.0095,-.016454,
-.006498,-.017854,
-.003299,-.018711,
0.0,-.019,
.003299,-.018711,
.006498,-.017854,
.0095,-.016454,
.012213,-.014555,
.014555,-.012213,
.016454,-.0095,
.017854,-.006498,
.018711,-.003299,
.019,0.0,
.018711,.003299,
.017854,.006498,
.016454,.0095,
.014555,.012213,
.012213,.014555,
.0095,.016454,
.006498,.017854,
.003299,.018711,
0.0,.019,
270.*
%
%ADD36MACRO36*%
%AMMACRO21*
4,1,36,.0025,0.0,
.002462,.000434,
.002349,.000855,
.002165,.00125,
.001915,.001607,
.001607,.001915,
.00125,.002165,
.000855,.002349,
.000434,.002462,
0.0,.0025,
-.000434,.002462,
-.000855,.002349,
-.00125,.002165,
-.001607,.001915,
-.001915,.001607,
-.002165,.00125,
-.002349,.000855,
-.002462,.000434,
-.0025,0.0,
-.002462,-.000434,
-.002349,-.000855,
-.002165,-.00125,
-.001915,-.001607,
-.001607,-.001915,
-.00125,-.002165,
-.000855,-.002349,
-.000434,-.002462,
0.0,-.0025,
.000434,-.002462,
.000855,-.002349,
.00125,-.002165,
.001607,-.001915,
.001915,-.001607,
.002165,-.00125,
.002349,-.000855,
.002462,-.000434,
.0025,0.0,
0.0*
%
%ADD21MACRO21*%
%AMMACRO17*
4,1,15,.02217,.01156,
.023841,.007535,
.024787,.00328,
.02498,-.001074,
.024414,-.005395,
.023106,-.009553,
.02217,-.01156,
.0273,-.01669,
.029783,-.011696,
.031362,-.006346,
.031987,-.000804,
.031641,.004763,
.030333,.010185,
.028104,.015297,
.0273,.01669,
.02217,.01156,
270.*
4,1,15,.01156,-.02217,
.007535,-.023841,
.00328,-.024787,
-.001074,-.02498,
-.005395,-.024414,
-.009553,-.023106,
-.01156,-.02217,
-.01669,-.0273,
-.011696,-.029783,
-.006346,-.031362,
-.000804,-.031987,
.004763,-.031641,
.010185,-.030333,
.015297,-.028104,
.01669,-.0273,
.01156,-.02217,
270.*
4,1,15,-.02217,-.01156,
-.023841,-.007535,
-.024787,-.00328,
-.02498,.001074,
-.024414,.005395,
-.023106,.009553,
-.02217,.01156,
-.0273,.01669,
-.029783,.011696,
-.031362,.006346,
-.031987,.000804,
-.031641,-.004763,
-.030333,-.010185,
-.028104,-.015297,
-.0273,-.01669,
-.02217,-.01156,
270.*
4,1,15,-.01156,.02217,
-.007535,.023841,
-.00328,.024787,
.001074,.02498,
.005395,.024414,
.009553,.023106,
.01156,.02217,
.01669,.0273,
.011696,.029783,
.006346,.031362,
.000804,.031987,
-.004763,.031641,
-.010185,.030333,
-.015297,.028104,
-.01669,.0273,
-.01156,.02217,
270.*
%
%ADD17MACRO17*%
%AMMACRO32*
4,1,15,.02438,.01377,
.026401,.009327,
.027619,.004601,
.027999,-.000265,
.027527,-.005123,
.02622,-.009825,
.02438,-.01377,
.02948,-.01887,
.032309,-.013464,
.034156,-.007649,
.034965,-.001602,
.034712,.004494,
.033405,.010454,
.031082,.016095,
.02948,.01887,
.02438,.01377,
270.*
4,1,15,.01377,-.02438,
.009327,-.026401,
.004601,-.027619,
-.000265,-.027999,
-.005123,-.027527,
-.009825,-.02622,
-.01377,-.02438,
-.01887,-.02948,
-.013464,-.032309,
-.007649,-.034156,
-.001602,-.034965,
.004494,-.034712,
.010454,-.033405,
.016095,-.031082,
.01887,-.02948,
.01377,-.02438,
270.*
4,1,15,-.02438,-.01377,
-.026401,-.009327,
-.027619,-.004601,
-.027999,.000265,
-.027527,.005123,
-.02622,.009825,
-.02438,.01377,
-.02948,.01887,
-.032309,.013464,
-.034156,.007649,
-.034965,.001602,
-.034712,-.004494,
-.033405,-.010454,
-.031082,-.016095,
-.02948,-.01887,
-.02438,-.01377,
270.*
4,1,15,-.01377,.02438,
-.009327,.026401,
-.004601,.027619,
.000265,.027999,
.005123,.027527,
.009825,.02622,
.01377,.02438,
.01887,.02948,
.013464,.032309,
.007649,.034156,
.001602,.034965,
-.004494,.034712,
-.010454,.033405,
-.016095,.031082,
-.01887,.02948,
-.01377,.02438,
270.*
%
%ADD32MACRO32*%
%AMMACRO15*
4,1,15,.02475,.01414,
.026829,.009627,
.028094,.004822,
.028504,-.000129,
.028049,-.005077,
.026741,-.009871,
.02475,-.01414,
.02984,-.01923,
.032726,-.013756,
.034617,-.007864,
.035457,-.001734,
.03522,.00445,
.033912,.010498,
.031574,.016227,
.02984,.01923,
.02475,.01414,
270.*
4,1,15,.01414,-.02475,
.009627,-.026829,
.004822,-.028094,
-.000129,-.028504,
-.005077,-.028049,
-.009871,-.026741,
-.01414,-.02475,
-.01923,-.02984,
-.013756,-.032726,
-.007864,-.034617,
-.001734,-.035457,
.00445,-.03522,
.010498,-.033912,
.016227,-.031574,
.01923,-.02984,
.01414,-.02475,
270.*
4,1,15,-.02475,-.01414,
-.026829,-.009627,
-.028094,-.004822,
-.028504,.000129,
-.028049,.005077,
-.026741,.009871,
-.02475,.01414,
-.02984,.01923,
-.032726,.013756,
-.034617,.007864,
-.035457,.001734,
-.03522,-.00445,
-.033912,-.010498,
-.031574,-.016227,
-.02984,-.01923,
-.02475,-.01414,
270.*
4,1,15,-.01414,.02475,
-.009627,.026829,
-.004822,.028094,
.000129,.028504,
.005077,.028049,
.009871,.026741,
.01414,.02475,
.01923,.02984,
.013756,.032726,
.007864,.034617,
.001734,.035457,
-.00445,.03522,
-.010498,.033912,
-.016227,.031574,
-.01923,.02984,
-.01414,.02475,
270.*
%
%ADD15MACRO15*%
%AMMACRO45*
4,1,18,.10783,.07955,
.120006,.059617,
.128535,.037873,
.133159,.014977,
.133736,-.008373,
.130251,-.031469,
.122807,-.053609,
.111633,-.074119,
.10783,-.07955,
.11284,-.08455,
.125808,-.063671,
.134953,-.040857,
.139997,-.016802,
.140788,.007763,
.137301,.032093,
.129642,.055447,
.118045,.077117,
.11284,.08455,
.10783,.07955,
270.*
4,1,18,.07955,-.10783,
.059617,-.120006,
.037873,-.128535,
.014977,-.133159,
-.008373,-.133736,
-.031469,-.130251,
-.053609,-.122807,
-.074119,-.111633,
-.07955,-.10783,
-.08455,-.11284,
-.063671,-.125808,
-.040857,-.134953,
-.016802,-.139997,
.007763,-.140788,
.032093,-.137301,
.055447,-.129642,
.077117,-.118045,
.08455,-.11284,
.07955,-.10783,
270.*
4,1,18,-.10783,-.07955,
-.120006,-.059617,
-.128535,-.037873,
-.133159,-.014977,
-.133736,.008373,
-.130251,.031469,
-.122807,.053609,
-.111633,.074119,
-.10783,.07955,
-.11284,.08455,
-.125808,.063671,
-.134953,.040857,
-.139997,.016802,
-.140788,-.007763,
-.137301,-.032093,
-.129642,-.055447,
-.118045,-.077117,
-.11284,-.08455,
-.10783,-.07955,
270.*
4,1,18,-.07955,.10783,
-.059617,.120006,
-.037873,.128535,
-.014977,.133159,
.008373,.133736,
.031469,.130251,
.053609,.122807,
.074119,.111633,
.07955,.10783,
.08455,.11284,
.063671,.125808,
.040857,.134953,
.016802,.139997,
-.007763,.140788,
-.032093,.137301,
-.055447,.129642,
-.077117,.118045,
-.08455,.11284,
-.07955,.10783,
270.*
%
%ADD45MACRO45*%
%AMMACRO37*
4,1,15,.03682,.01914,
.039584,.012455,
.041146,.005393,
.041457,-.001834,
.040509,-.009005,
.03833,-.015903,
.03682,-.01914,
.04197,-.0243,
.045552,-.016643,
.04775,-.00848,
.048497,-.000059,
.047771,.008363,
.045593,.016531,
.042029,.024197,
.04197,.0243,
.03682,.01914,
270.*
4,1,15,.01914,-.03682,
.012455,-.039584,
.005393,-.041146,
-.001834,-.041457,
-.009005,-.040509,
-.015903,-.03833,
-.01914,-.03682,
-.0243,-.04197,
-.016643,-.045552,
-.00848,-.04775,
-.000059,-.048497,
.008363,-.047771,
.016531,-.045593,
.024197,-.042029,
.0243,-.04197,
.01914,-.03682,
270.*
4,1,15,-.03682,-.01914,
-.039584,-.012455,
-.041146,-.005393,
-.041457,.001834,
-.040509,.009005,
-.03833,.015903,
-.03682,.01914,
-.04197,.0243,
-.045552,.016643,
-.04775,.00848,
-.048497,.000059,
-.047771,-.008363,
-.045593,-.016531,
-.042029,-.024197,
-.04197,-.0243,
-.03682,-.01914,
270.*
4,1,15,-.01914,.03682,
-.012455,.039584,
-.005393,.041146,
.001834,.041457,
.009005,.040509,
.015903,.03833,
.01914,.03682,
.0243,.04197,
.016643,.045552,
.00848,.04775,
.000059,.048497,
-.008363,.047771,
-.016531,.045593,
-.024197,.042029,
-.0243,.04197,
-.01914,.03682,
270.*
%
%ADD37MACRO37*%
%AMMACRO33*
4,1,17,.03273,.02212,
.036074,.0161,
.038322,.009592,
.039405,.002791,
.039291,-.004094,
.037983,-.010854,
.035521,-.017285,
.03273,-.02212,
.03775,-.02715,
.041891,-.020182,
.044759,-.012601,
.046267,-.004638,
.04637,.003467,
.045063,.011466,
.042388,.019117,
.038424,.026188,
.03775,.02715,
.03273,.02212,
270.*
4,1,17,.02212,-.03273,
.0161,-.036074,
.009592,-.038322,
.002791,-.039405,
-.004094,-.039291,
-.010854,-.037983,
-.017285,-.035521,
-.02212,-.03273,
-.02715,-.03775,
-.020182,-.041891,
-.012601,-.044759,
-.004638,-.046267,
.003467,-.04637,
.011466,-.045063,
.019117,-.042388,
.026188,-.038424,
.02715,-.03775,
.02212,-.03273,
270.*
4,1,17,-.03273,-.02212,
-.036074,-.0161,
-.038322,-.009592,
-.039405,-.002791,
-.039291,.004094,
-.037983,.010854,
-.035521,.017285,
-.03273,.02212,
-.03775,.02715,
-.041891,.020182,
-.044759,.012601,
-.046267,.004638,
-.04637,-.003467,
-.045063,-.011466,
-.042388,-.019117,
-.038424,-.026188,
-.03775,-.02715,
-.03273,-.02212,
270.*
4,1,17,-.02212,.03273,
-.0161,.036074,
-.009592,.038322,
-.002791,.039405,
.004094,.039291,
.010854,.037983,
.017285,.035521,
.02212,.03273,
.02715,.03775,
.020182,.041891,
.012601,.044759,
.004638,.046267,
-.003467,.04637,
-.011466,.045063,
-.019117,.042388,
-.026188,.038424,
-.02715,.03775,
-.02212,.03273,
270.*
%
%ADD33MACRO33*%
%AMMACRO39*
4,1,15,-.03682,.01914,
-.039584,.012455,
-.041146,.005393,
-.041457,-.001834,
-.040509,-.009005,
-.03833,-.015903,
-.03682,-.01914,
-.04197,-.0243,
-.045552,-.016643,
-.04775,-.00848,
-.048497,-.000059,
-.047771,.008363,
-.045593,.016531,
-.042029,.024197,
-.04197,.0243,
-.03682,.01914,
270.*
4,1,15,-.01914,-.03682,
-.012455,-.039584,
-.005393,-.041146,
.001834,-.041457,
.009005,-.040509,
.015903,-.03833,
.01914,-.03682,
.0243,-.04197,
.016643,-.045552,
.00848,-.04775,
.000059,-.048497,
-.008363,-.047771,
-.016531,-.045593,
-.024197,-.042029,
-.0243,-.04197,
-.01914,-.03682,
270.*
4,1,15,.03682,-.01914,
.039584,-.012455,
.041146,-.005393,
.041457,.001834,
.040509,.009005,
.03833,.015903,
.03682,.01914,
.04197,.0243,
.045552,.016643,
.04775,.00848,
.048497,.000059,
.047771,-.008363,
.045593,-.016531,
.042029,-.024197,
.04197,-.0243,
.03682,-.01914,
270.*
4,1,15,.01914,.03682,
.012455,.039584,
.005393,.041146,
-.001834,.041457,
-.009005,.040509,
-.015903,.03833,
-.01914,.03682,
-.0243,.04197,
-.016643,.045552,
-.00848,.04775,
-.000059,.048497,
.008363,.047771,
.016531,.045593,
.024197,.042029,
.0243,.04197,
.01914,.03682,
270.*
%
%ADD39MACRO39*%
%ADD47C,.006*%
%ADD55C,.07004*%
%ADD49C,.07006*%
%ADD50C,.11022*%
%ADD54C,.10006*%
%ADD57C,.11006*%
%ADD58C,.11206*%
%ADD51C,.12707*%
%ADD52C,.16506*%
%ADD53C,.19606*%
%ADD48C,.28606*%
%ADD56C,.32598*%
G75*
%LPD*%
G75*
G36*
G01X-297025Y-1013390D02*
X3691357D01*
Y1828909D01*
X-297025D01*
Y-1013390D01*
G37*
%LPC*%
G75*
G36*
G01X1261706Y574740D02*
X1271654D01*
G02X1277907Y573440I1J-15685D01*
G02X1278016Y573321I-80J-183D01*
G03X1279438Y572304I1422J486D01*
G03X1279840Y572359I-1J1502D01*
G02X1280000Y572335I53J-193D01*
G02X1286280Y564721I-8346J-13280D01*
G02X1286272Y564560I-187J-71D01*
G03X1286114Y563889I1344J-671D01*
G03X1286870Y562585I1503J0D01*
G02X1286966Y562455I-99J-174D01*
G02X1287339Y559055I-15312J-3400D01*
G01Y552177D01*
G02X1287279Y552034I-200J0D01*
G03Y549890I1052J-1072D01*
G02X1287339Y549747I-140J-143D01*
G01Y532177D01*
G02X1287279Y532034I-200J0D01*
G03Y529890I1052J-1072D01*
G02X1287339Y529747I-140J-143D01*
G01Y512177D01*
G02X1287279Y512034I-200J0D01*
G03Y509890I1052J-1072D01*
G02X1287339Y509747I-140J-143D01*
G01Y492177D01*
G02X1287279Y492034I-200J0D01*
G03Y489890I1052J-1072D01*
G02X1287339Y489747I-140J-143D01*
G01Y472177D01*
G02X1287279Y472034I-200J0D01*
G03Y469890I1052J-1072D01*
G02X1287339Y469747I-140J-143D01*
G01Y452177D01*
G02X1287279Y452034I-200J0D01*
G03Y449890I1052J-1072D01*
G02X1287339Y449747I-140J-143D01*
G01Y432177D01*
G02X1287279Y432034I-200J0D01*
G03Y429890I1052J-1072D01*
G02X1287339Y429747I-140J-143D01*
G01Y412177D01*
G02X1287279Y412034I-200J0D01*
G03Y409890I1052J-1072D01*
G02X1287339Y409747I-140J-143D01*
G01Y392177D01*
G02X1287279Y392034I-200J0D01*
G03Y389890I1052J-1072D01*
G02X1287339Y389747I-140J-143D01*
G01Y372177D01*
G02X1287279Y372034I-200J0D01*
G03Y369890I1052J-1072D01*
G02X1287339Y369747I-140J-143D01*
G01Y352177D01*
G02X1287279Y352034I-200J0D01*
G03Y349890I1052J-1072D01*
G02X1287339Y349747I-140J-143D01*
G01Y332177D01*
G02X1287279Y332034I-200J0D01*
G03Y329890I1052J-1072D01*
G02X1287339Y329747I-140J-143D01*
G01Y312177D01*
G02X1287279Y312034I-200J0D01*
G03Y309890I1052J-1072D01*
G02X1287339Y309747I-140J-143D01*
G01Y292177D01*
G02X1287279Y292034I-200J0D01*
G03Y289890I1052J-1072D01*
G02X1287339Y289747I-140J-143D01*
G01Y272177D01*
G02X1287279Y272034I-200J0D01*
G03Y269890I1052J-1072D01*
G02X1287339Y269747I-140J-143D01*
G01Y252177D01*
G02X1287279Y252034I-200J0D01*
G03Y249890I1052J-1072D01*
G02X1287339Y249747I-140J-143D01*
G01Y232177D01*
G02X1287279Y232034I-200J0D01*
G03Y229890I1052J-1072D01*
G02X1287339Y229747I-140J-143D01*
G01Y212177D01*
G02X1287279Y212034I-200J0D01*
G03Y209890I1052J-1072D01*
G02X1287339Y209747I-140J-143D01*
G01Y192177D01*
G02X1287279Y192034I-200J0D01*
G03Y189890I1052J-1072D01*
G02X1287339Y189747I-140J-143D01*
G01Y172177D01*
G02X1287279Y172034I-200J0D01*
G03Y169890I1052J-1072D01*
G02X1287339Y169747I-140J-143D01*
G01Y152177D01*
G02X1287279Y152034I-200J0D01*
G03Y149890I1052J-1072D01*
G02X1287339Y149747I-140J-143D01*
G01Y132177D01*
G02X1287279Y132034I-200J0D01*
G03Y129890I1052J-1072D01*
G02X1287339Y129747I-140J-143D01*
G01Y112177D01*
G02X1287279Y112034I-200J0D01*
G03Y109890I1052J-1072D01*
G02X1287339Y109747I-140J-143D01*
G01Y92177D01*
G02X1287279Y92034I-200J0D01*
G03Y89890I1052J-1072D01*
G02X1287339Y89747I-140J-143D01*
G01Y72177D01*
G02X1287279Y72034I-200J0D01*
G03Y69890I1052J-1072D01*
G02X1287339Y69747I-140J-143D01*
G01Y52177D01*
G02X1287279Y52034I-200J0D01*
G03Y49890I1052J-1072D01*
G02X1287339Y49747I-140J-143D01*
G01Y32177D01*
G02X1287279Y32034I-200J0D01*
G03Y29890I1052J-1072D01*
G02X1287339Y29747I-140J-143D01*
G01Y19685D01*
G02X1286329Y14147I-15685J-1D01*
G02X1286215Y14031I-187J70D01*
G03X1285264Y12634I551J-1397D01*
G03X1285341Y12159I1502J0D01*
G02X1285326Y11997I-190J-64D01*
G02X1278392Y5521I-13672J7688D01*
G02X1278230Y5517I-86J181D01*
G03X1277657Y5630I-572J-1389D01*
G03X1276300Y4772I0J-1502D01*
G02X1276177Y4666I-181J86D01*
G02X1271654Y4000I-4522J15019D01*
G01X1255793D01*
G02X1255651Y4059I0J200D01*
G03X1253513I-1069J-1055D01*
G02X1253371Y4000I-142J141D01*
G01X1235793D01*
G02X1235651Y4059I0J200D01*
G03X1233513I-1069J-1055D01*
G02X1233371Y4000I-142J141D01*
G01X1215793D01*
G02X1215651Y4059I0J200D01*
G03X1213513I-1069J-1055D01*
G02X1213371Y4000I-142J141D01*
G01X1195793D01*
G02X1195651Y4059I0J200D01*
G03X1193513I-1069J-1055D01*
G02X1193371Y4000I-142J141D01*
G01X1175793D01*
G02X1175651Y4059I0J200D01*
G03X1173513I-1069J-1055D01*
G02X1173371Y4000I-142J141D01*
G01X1155793D01*
G02X1155651Y4059I0J200D01*
G03X1153513I-1069J-1055D01*
G02X1153371Y4000I-142J141D01*
G01X1135793D01*
G02X1135651Y4059I0J200D01*
G03X1133513I-1069J-1055D01*
G02X1133371Y4000I-142J141D01*
G01X1115793D01*
G02X1115651Y4059I0J200D01*
G03X1113513I-1069J-1055D01*
G02X1113371Y4000I-142J141D01*
G01X1095793D01*
G02X1095651Y4059I0J200D01*
G03X1093513I-1069J-1055D01*
G02X1093371Y4000I-142J141D01*
G01X1075793D01*
G02X1075651Y4059I0J200D01*
G03X1073513I-1069J-1055D01*
G02X1073371Y4000I-142J141D01*
G01X1055793D01*
G02X1055651Y4059I0J200D01*
G03X1053513I-1069J-1055D01*
G02X1053371Y4000I-142J141D01*
G01X1035793D01*
G02X1035651Y4059I0J200D01*
G03X1033513I-1069J-1055D01*
G02X1033371Y4000I-142J141D01*
G01X1015793D01*
G02X1015651Y4059I0J200D01*
G03X1013513I-1069J-1055D01*
G02X1013371Y4000I-142J141D01*
G01X995793D01*
G02X995651Y4059I0J200D01*
G03X993513I-1069J-1055D01*
G02X993371Y4000I-142J141D01*
G01X975793D01*
G02X975651Y4059I0J200D01*
G03X973513I-1069J-1055D01*
G02X973371Y4000I-142J141D01*
G01X955793D01*
G02X955651Y4059I0J200D01*
G03X953513I-1069J-1055D01*
G02X953371Y4000I-142J141D01*
G01X935793D01*
G02X935651Y4059I0J200D01*
G03X933513I-1069J-1055D01*
G02X933371Y4000I-142J141D01*
G01X915793D01*
G02X915651Y4059I0J200D01*
G03X913513I-1069J-1055D01*
G02X913371Y4000I-142J141D01*
G01X895793D01*
G02X895651Y4059I0J200D01*
G03X893513I-1069J-1055D01*
G02X893371Y4000I-142J141D01*
G01X875793D01*
G02X875651Y4059I0J200D01*
G03X873513I-1069J-1055D01*
G02X873371Y4000I-142J141D01*
G01X855793D01*
G02X855651Y4059I0J200D01*
G03X853513I-1069J-1055D01*
G02X853371Y4000I-142J141D01*
G01X835793D01*
G02X835651Y4059I0J200D01*
G03X833513I-1069J-1055D01*
G02X833371Y4000I-142J141D01*
G01X815793D01*
G02X815651Y4059I0J200D01*
G03X813513I-1069J-1055D01*
G02X813371Y4000I-142J141D01*
G01X795793D01*
G02X795651Y4059I0J200D01*
G03X793513I-1069J-1055D01*
G02X793371Y4000I-142J141D01*
G01X775793D01*
G02X775651Y4059I0J200D01*
G03X773513I-1069J-1055D01*
G02X773371Y4000I-142J141D01*
G01X755793D01*
G02X755651Y4059I0J200D01*
G03X753513I-1069J-1055D01*
G02X753371Y4000I-142J141D01*
G01X735793D01*
G02X735651Y4059I0J200D01*
G03X733513I-1069J-1055D01*
G02X733371Y4000I-142J141D01*
G01X715793D01*
G02X715651Y4059I0J200D01*
G03X713513I-1069J-1055D01*
G02X713371Y4000I-142J141D01*
G01X695793D01*
G02X695651Y4059I0J200D01*
G03X693513I-1069J-1055D01*
G02X693371Y4000I-142J141D01*
G01X675793D01*
G02X675651Y4059I0J200D01*
G03X673513I-1069J-1055D01*
G02X673371Y4000I-142J141D01*
G01X655793D01*
G02X655651Y4059I0J200D01*
G03X653513I-1069J-1055D01*
G02X653371Y4000I-142J141D01*
G01X635793D01*
G02X635651Y4059I0J200D01*
G03X633513I-1069J-1055D01*
G02X633371Y4000I-142J141D01*
G01X615793D01*
G02X615651Y4059I0J200D01*
G03X613513I-1069J-1055D01*
G02X613371Y4000I-142J141D01*
G01X595793D01*
G02X595651Y4059I0J200D01*
G03X593513I-1069J-1055D01*
G02X593371Y4000I-142J141D01*
G01X575793D01*
G02X575651Y4059I0J200D01*
G03X573513I-1069J-1055D01*
G02X573371Y4000I-142J141D01*
G01X555793D01*
G02X555651Y4059I0J200D01*
G03X553513I-1069J-1055D01*
G02X553371Y4000I-142J141D01*
G01X535793D01*
G02X535651Y4059I0J200D01*
G03X533513I-1069J-1055D01*
G02X533371Y4000I-142J141D01*
G01X515793D01*
G02X515651Y4059I0J200D01*
G03X513513I-1069J-1055D01*
G02X513371Y4000I-142J141D01*
G01X495793D01*
G02X495651Y4059I0J200D01*
G03X493513I-1069J-1055D01*
G02X493371Y4000I-142J141D01*
G01X475793D01*
G02X475651Y4059I0J200D01*
G03X473513I-1069J-1055D01*
G02X473371Y4000I-142J141D01*
G01X455793D01*
G02X455651Y4059I0J200D01*
G03X453513I-1069J-1055D01*
G02X453371Y4000I-142J141D01*
G01X435793D01*
G02X435651Y4059I0J200D01*
G03X433513I-1069J-1055D01*
G02X433371Y4000I-142J141D01*
G01X415793D01*
G02X415651Y4059I0J200D01*
G03X413513I-1069J-1055D01*
G02X413371Y4000I-142J141D01*
G01X395793D01*
G02X395651Y4059I0J200D01*
G03X393513I-1069J-1055D01*
G02X393371Y4000I-142J141D01*
G01X375793D01*
G02X375651Y4059I0J200D01*
G03X373513I-1069J-1055D01*
G02X373371Y4000I-142J141D01*
G01X355793D01*
G02X355651Y4059I0J200D01*
G03X353513I-1069J-1055D01*
G02X353371Y4000I-142J141D01*
G01X335793D01*
G02X335651Y4059I0J200D01*
G03X333513I-1069J-1055D01*
G02X333371Y4000I-142J141D01*
G01X315793D01*
G02X315651Y4059I0J200D01*
G03X313513I-1069J-1055D01*
G02X313371Y4000I-142J141D01*
G01X295793D01*
G02X295651Y4059I0J200D01*
G03X293513I-1069J-1055D01*
G02X293371Y4000I-142J141D01*
G01X275793D01*
G02X275651Y4059I0J200D01*
G03X273513I-1069J-1055D01*
G02X273371Y4000I-142J141D01*
G01X255793D01*
G02X255651Y4059I0J200D01*
G03X253513I-1069J-1055D01*
G02X253371Y4000I-142J141D01*
G01X235793D01*
G02X235651Y4059I0J200D01*
G03X233513I-1069J-1055D01*
G02X233371Y4000I-142J141D01*
G01X215793D01*
G02X215651Y4059I0J200D01*
G03X213513I-1069J-1055D01*
G02X213371Y4000I-142J141D01*
G01X195793D01*
G02X195651Y4059I0J200D01*
G03X193513I-1069J-1055D01*
G02X193371Y4000I-142J141D01*
G01X175793D01*
G02X175651Y4059I0J200D01*
G03X173513I-1069J-1055D01*
G02X173371Y4000I-142J141D01*
G01X155793D01*
G02X155651Y4059I0J200D01*
G03X153513I-1069J-1055D01*
G02X153371Y4000I-142J141D01*
G01X135793D01*
G02X135651Y4059I0J200D01*
G03X133513I-1069J-1055D01*
G02X133371Y4000I-142J141D01*
G01X115793D01*
G02X115651Y4059I0J200D01*
G03X113513I-1069J-1055D01*
G02X113371Y4000I-142J141D01*
G01X95793D01*
G02X95651Y4059I0J200D01*
G03X93513I-1069J-1055D01*
G02X93371Y4000I-142J141D01*
G01X75793D01*
G02X75651Y4059I0J200D01*
G03X73513I-1069J-1055D01*
G02X73371Y4000I-142J141D01*
G01X55793D01*
G02X55651Y4059I0J200D01*
G03X53513I-1069J-1055D01*
G02X53371Y4000I-142J141D01*
G01X35793D01*
G02X35651Y4059I0J200D01*
G03X33513I-1069J-1055D01*
G02X33371Y4000I-142J141D01*
G01X19685D01*
G02X16244Y4382I0J15685D01*
G02X16115Y4478I45J195D01*
G03X14811Y5234I-1304J-747D01*
G03X14147Y5079I0J-1502D01*
G02X13986Y5072I-88J179D01*
G02X4036Y18619I5699J14613D01*
G02X4091Y18771I200J14D01*
G03X4507Y19808I-1086J1038D01*
G03X4060Y20878I-1502J1D01*
G02X4000Y21020I140J143D01*
G01Y33596D01*
G02X4060Y33738I200J-1D01*
G03X4507Y34808I-1055J1069D01*
G03X4060Y35878I-1502J1D01*
G02X4000Y36020I140J143D01*
G01Y58596D01*
G02X4060Y58738I200J-1D01*
G03X4507Y59808I-1055J1069D01*
G03X4060Y60878I-1502J1D01*
G02X4000Y61020I140J143D01*
G01Y63268D01*
G02X11551Y71075I7811J0D01*
G02X11699Y71015I5J-200D01*
G03X12767Y70570I1067J1057D01*
G03X13838Y71019I0J1502D01*
G02X13981Y71079I143J-140D01*
G01X37796D01*
G03X43764Y77046I0J5969D01*
G01Y122324D01*
G03X37796Y128291I-5968J-2D01*
G01X28485D01*
G02X28342Y128351I0J200D01*
G03X26200I-1071J-1053D01*
G02X26057Y128291I-143J140D01*
G01X11811D01*
G02X9126Y128767I0J7811D01*
G02X9006Y128887I68J188D01*
G03X7595Y129875I-1411J-514D01*
G03X7263Y129838I-1J-1502D01*
G02X7098Y129873I-45J195D01*
G02X4000Y136102I4713J6229D01*
G01Y144026D01*
G02X4060Y144168I200J-1D01*
G03X4507Y145238I-1055J1069D01*
G03X4060Y146308I-1502J1D01*
G02X4000Y146450I140J143D01*
G01Y164026D01*
G02X4060Y164168I200J-1D01*
G03X4507Y165238I-1055J1069D01*
G03X4060Y166308I-1502J1D01*
G02X4000Y166450I140J143D01*
G01Y184026D01*
G02X4060Y184168I200J-1D01*
G03X4507Y185238I-1055J1069D01*
G03X4060Y186308I-1502J1D01*
G02X4000Y186450I140J143D01*
G01Y204026D01*
G02X4060Y204168I200J-1D01*
G03X4507Y205238I-1055J1069D01*
G03X4060Y206308I-1502J1D01*
G02X4000Y206450I140J143D01*
G01Y224026D01*
G02X4060Y224168I200J-1D01*
G03X4507Y225238I-1055J1069D01*
G03X4060Y226308I-1502J1D01*
G02X4000Y226450I140J143D01*
G01Y244026D01*
G02X4060Y244168I200J-1D01*
G03X4507Y245238I-1055J1069D01*
G03X4060Y246308I-1502J1D01*
G02X4000Y246450I140J143D01*
G01Y264026D01*
G02X4060Y264168I200J-1D01*
G03X4507Y265238I-1055J1069D01*
G03X4060Y266308I-1502J1D01*
G02X4000Y266450I140J143D01*
G01Y284026D01*
G02X4060Y284168I200J-1D01*
G03X4507Y285238I-1055J1069D01*
G03X4060Y286308I-1502J1D01*
G02X4000Y286450I140J143D01*
G01Y304026D01*
G02X4060Y304168I200J-1D01*
G03X4507Y305238I-1055J1069D01*
G03X4060Y306308I-1502J1D01*
G02X4000Y306450I140J143D01*
G01Y324026D01*
G02X4060Y324168I200J-1D01*
G03X4507Y325238I-1055J1069D01*
G03X4060Y326308I-1502J1D01*
G02X4000Y326450I140J143D01*
G01Y344026D01*
G02X4060Y344168I200J-1D01*
G03X4507Y345238I-1055J1069D01*
G03X4060Y346308I-1502J1D01*
G02X4000Y346450I140J143D01*
G01Y364026D01*
G02X4060Y364168I200J-1D01*
G03X4507Y365238I-1055J1069D01*
G03X4060Y366308I-1502J1D01*
G02X4000Y366450I140J143D01*
G01Y384026D01*
G02X4060Y384168I200J-1D01*
G03X4507Y385238I-1055J1069D01*
G03X4060Y386308I-1502J1D01*
G02X4000Y386450I140J143D01*
G01Y404026D01*
G02X4060Y404168I200J-1D01*
G03X4507Y405238I-1055J1069D01*
G03X4060Y406308I-1502J1D01*
G02X4000Y406450I140J143D01*
G01Y424026D01*
G02X4060Y424168I200J-1D01*
G03X4507Y425238I-1055J1069D01*
G03X4060Y426308I-1502J1D01*
G02X4000Y426450I140J143D01*
G01Y444026D01*
G02X4060Y444168I200J-1D01*
G03X4507Y445238I-1055J1069D01*
G03X4083Y446284I-1502J0D01*
G02X4027Y446440I143J140D01*
G02X11811Y453598I7784J-653D01*
G01X18342D01*
G02X18485Y453538I0J-200D01*
G03X20631I1073J1051D01*
G02X20774Y453598I143J-140D01*
G01X37795D01*
G03X38639Y453658I0J5969D01*
G02X38771Y453631I28J-198D01*
G03X39549Y453414I778J1286D01*
G03X40982Y454465I0J1502D01*
G02X41063Y454572I191J-60D01*
G03X43764Y459567I-3268J4995D01*
G01Y504844D01*
G03X37796Y510811I-5968J-2D01*
G01X11811D01*
G02X11274Y510829I-7J7811D01*
G02X11126Y510911I14J200D01*
G03X9913Y511528I-1213J-884D01*
G03X9185Y511340I0J-1502D01*
G02X9017Y511328I-97J175D01*
G02X4000Y518622I2794J7294D01*
G01Y523083D01*
G02X4062Y523227I200J-1D01*
G03Y525397I-1040J1085D01*
G02X4000Y525541I138J145D01*
G01Y548083D01*
G02X4062Y548227I200J-1D01*
G03Y550397I-1040J1085D01*
G02X4000Y550541I138J145D01*
G01Y559055D01*
G02X4970Y564486I15685J1D01*
G02X5085Y564604I188J-68D01*
G03X6042Y566003I-544J1399D01*
G03X5957Y566502I-1502J1D01*
G02X5970Y566666I188J68D01*
G02X19290Y574735I13715J-7611D01*
G02X19436Y574677I5J-200D01*
G03X20498Y574237I1062J1062D01*
G03X21564Y574681I0J1502D01*
G02X21706Y574740I142J-141D01*
G01X39290D01*
G02X39432Y574681I0J-200D01*
G03X41564I1066J1058D01*
G02X41706Y574740I142J-141D01*
G01X59290D01*
G02X59432Y574681I0J-200D01*
G03X61564I1066J1058D01*
G02X61706Y574740I142J-141D01*
G01X79290D01*
G02X79432Y574681I0J-200D01*
G03X81564I1066J1058D01*
G02X81706Y574740I142J-141D01*
G01X99290D01*
G02X99432Y574681I0J-200D01*
G03X101564I1066J1058D01*
G02X101706Y574740I142J-141D01*
G01X119290D01*
G02X119432Y574681I0J-200D01*
G03X121564I1066J1058D01*
G02X121706Y574740I142J-141D01*
G01X139290D01*
G02X139432Y574681I0J-200D01*
G03X141564I1066J1058D01*
G02X141706Y574740I142J-141D01*
G01X150047D01*
G03X150102Y574683I1466J1360D01*
G01X153441Y571344D01*
G02X153500Y571202I-141J-142D01*
G01Y475411D01*
G02X153441Y475269I-200J0D01*
G01X148412Y470240D01*
G02X148270Y470181I-142J141D01*
G01X94082D01*
G02X93897Y470306I0J200D01*
G01X93734Y470706D01*
X93759Y470825D01*
X93804Y470868D01*
G03X98598Y482205I-11008J11337D01*
G03X82795Y498008I-15803J0D01*
G03X68500Y488942I0J-15803D01*
G01X68479Y488896D01*
X68400Y488837D01*
X67972Y488772D01*
X67879Y488804D01*
X67844Y488842D01*
G03Y475568I-7214J-6637D01*
G01X67879Y475606D01*
X67972Y475638D01*
X68400Y475573D01*
X68479Y475514D01*
X68500Y475468D01*
G03X71786Y470868I14294J6738D01*
G01X71831Y470825D01*
X71856Y470706D01*
X71693Y470306D01*
G02X71508Y470181I-185J75D01*
G01X63966D01*
G03X62552Y469595I0J-1999D01*
G01X58586Y465629D01*
G03X58000Y464215I1413J-1414D01*
G01Y309100D01*
G02X57800Y308900I-200J0D01*
G01X35100D01*
G03X33686Y308314I0J-1999D01*
G01X30686Y305314D01*
G03X30100Y303900I1413J-1414D01*
G01Y269900D01*
G03X30686Y268486I1999J0D01*
G01X34486Y264686D01*
G03X35900Y264100I1414J1413D01*
G01X105337D01*
G02X105513Y263995I0J-200D01*
G01X105706Y263637D01*
X105701Y263527D01*
X105671Y263481D01*
G03X105098Y261560I2929J-1920D01*
G03X105398Y260141I3502J-1D01*
G02Y259979I-183J-81D01*
G03X105098Y258560I3202J-1418D01*
G03X105398Y257141I3502J-1D01*
G02Y256979I-183J-81D01*
G03X105098Y255560I3202J-1418D01*
G03X108600Y252058I3502J0D01*
G03X110019Y252358I1J3502D01*
G02X110181I81J-183D01*
G03X111600Y252058I1418J3202D01*
G03X115102Y255560I0J3502D01*
G03X114802Y256979I-3502J1D01*
G02Y257141I183J81D01*
G03X115102Y258560I-3202J1418D01*
G03X114802Y259979I-3502J1D01*
G02Y260141I183J81D01*
G03X115102Y261560I-3202J1418D01*
G03X114529Y263481I-3502J1D01*
G01X114499Y263527D01*
X114494Y263637D01*
X114687Y263995D01*
G02X114863Y264100I176J-95D01*
G01X152389D01*
G02X152531Y264041I0J-200D01*
G01X153968Y262604D01*
G02X154027Y262462I-141J-142D01*
G01Y248224D01*
X153946Y248117D01*
X153882Y248099D01*
G03X151338Y244730I959J-3369D01*
G03X152046Y242618I3502J-1D01*
G01X152091Y242558D01*
X152081Y242409D01*
X136086Y226414D01*
G03X135500Y225000I1413J-1414D01*
G01Y182811D01*
G03X136086Y181397I1999J0D01*
G01X225086Y92397D01*
G03X226500Y91811I1414J1413D01*
G01X796811D01*
G03X798225Y92397I0J1999D01*
G01X805414Y99586D01*
G03X806000Y101000I-1413J1414D01*
G01Y177147D01*
G02X806059Y177289I200J0D01*
G01X808332Y179562D01*
G02X808474Y179621I142J-141D01*
G01X837002D01*
G03X838416Y180207I0J1999D01*
G01X844526Y186317D01*
G03X845112Y187731I-1413J1414D01*
G01Y255127D01*
G03X844526Y256541I-1999J0D01*
G01X839243Y261824D01*
X839228Y261860D01*
G03X837360Y263728I-3228J-1360D01*
G02X837297Y263770I77J184D01*
G01X829287Y271780D01*
G02X829243Y271846I141J142D01*
G03X827321Y273768I-3243J-1321D01*
G02X827255Y273812I76J185D01*
G01X805035Y296032D01*
G03X803621Y296618I-1414J-1413D01*
G01X695483D01*
G02X695356Y296663I-1J200D01*
G03X694406Y297002I-950J-1162D01*
G03X693435Y296646I0J-1502D01*
G02X693332Y296600I-130J152D01*
G03X692185Y296032I267J-1981D01*
G01X667712Y271559D01*
G02X667570Y271500I-142J141D01*
G01X649952D01*
G02X649810Y271559I0J200D01*
G01X625337Y296032D01*
G03X623923Y296618I-1414J-1413D01*
G01X536118D01*
G03X534704Y296032I0J-1999D01*
G01X510231Y271559D01*
G02X510089Y271500I-142J141D01*
G01X492471D01*
G02X492329Y271559I0J200D01*
G01X467856Y296032D01*
G03X466442Y296618I-1414J-1413D01*
G01X378637D01*
G03X377223Y296032I0J-1999D01*
G01X352750Y271559D01*
G02X352608Y271500I-142J141D01*
G01X334990D01*
G02X334848Y271559I0J200D01*
G01X310375Y296032D01*
G03X308961Y296618I-1414J-1413D01*
G01X221157D01*
G03X219743Y296032I0J-1999D01*
G01X195270Y271559D01*
G02X195128Y271500I-142J141D01*
G01X156938D01*
G02X156796Y271559I0J200D01*
G01X153059Y275296D01*
G02X153000Y275438I141J142D01*
G01Y293707D01*
G02X153059Y293849I200J0D01*
G01X185151Y325941D01*
G02X185293Y326000I142J-141D01*
G01X587000D01*
G03X588414Y326586I0J1999D01*
G01X619269Y357441D01*
G02X619411Y357500I142J-141D01*
G01X703301D01*
G02X703431Y357453I1J-200D01*
G03X704400Y357098I970J1147D01*
G03X705369Y357453I-1J1502D01*
G02X705499Y357500I129J-153D01*
G01X706859D01*
G02X706963Y357470I-1J-200D01*
G03X707750Y357248I786J1280D01*
G03X708537Y357470I1J1502D01*
G02X708641Y357500I105J-170D01*
G01X790508D01*
X790607Y357436D01*
X790631Y357382D01*
G03X793369I1369J618D01*
G01X793393Y357436D01*
X793492Y357500D01*
X825096D01*
G02X825199Y357472I1J-200D01*
G03X827000Y356973I1802J3003D01*
G03X828801Y357472I-1J3502D01*
G02X828904Y357500I102J-172D01*
G01X863293D01*
G02X863435Y357441I0J-200D01*
G03X863882Y357131I1065J1059D01*
G01X863936Y357107D01*
X864000Y357008D01*
Y314407D01*
G02X863941Y314265I-200J0D01*
G03Y312135I1059J-1065D01*
G02X864000Y311993I-141J-142D01*
G01Y286401D01*
G03X863999Y286341I1999J-63D01*
G03X864585Y284927I1999J0D01*
G01X901166Y248346D01*
G02X901211Y248133I-142J-141D01*
G01X901058Y247736D01*
X900963Y247667D01*
X900903Y247664D01*
G03X882198Y228001I983J-19663D01*
G03X901886Y208314I19687J0D01*
G01X988500D01*
G03X1002917Y214594I1J19687D01*
G01X1002945Y214624D01*
X1003019Y214657D01*
X1003348Y214663D01*
G02X1003493Y214604I3J-200D01*
G01X1016206Y201891D01*
G02X1016256Y201689I-141J-142D01*
G01X1016133Y201298D01*
X1016049Y201224D01*
X1015994Y201214D01*
G03X1013112Y197767I620J-3447D01*
G03X1020116I3502J0D01*
G03X1019023Y200310I-3502J1D01*
G01X1018978Y200352D01*
X1018952Y200472D01*
X1019112Y200874D01*
G02X1019298Y201000I186J-74D01*
G01X1064589D01*
G02X1064731Y200941I0J-200D01*
G01X1067941Y197731D01*
G02X1068000Y197589I-141J-142D01*
G01Y180868D01*
G02X1067957Y180745I-200J1D01*
G03Y176425I2759J-2160D01*
G02X1068000Y176302I-157J-124D01*
G01Y170000D01*
G03X1068586Y168586I1999J0D01*
G01X1077586Y159586D01*
G03X1079000Y159000I1414J1413D01*
G01X1082830D01*
X1082937Y158919D01*
X1082955Y158854D01*
G03X1085847I1446J406D01*
G01X1085865Y158919D01*
X1085972Y159000D01*
X1090508D01*
X1090607Y158936D01*
X1090631Y158882D01*
G03X1093369I1369J618D01*
G01X1093393Y158936D01*
X1093492Y159000D01*
X1110589D01*
G02X1110731Y158941I0J-200D01*
G01X1115441Y154231D01*
G02X1115500Y154089I-141J-142D01*
G01Y130192D01*
X1115402Y130080D01*
X1115327Y130070D01*
G03Y123130I473J-3470D01*
G01X1115402Y123120D01*
X1115500Y123008D01*
Y118500D01*
G03X1116086Y117086I1999J0D01*
G01X1118086Y115086D01*
G03X1119500Y114500I1414J1413D01*
G01X1138964D01*
G03X1140378Y115086I0J1999D01*
G01X1141914Y116622D01*
G03X1142500Y118036I-1413J1414D01*
G01Y119293D01*
G02X1142559Y119435I200J0D01*
G03Y121565I-1059J1065D01*
G02X1142500Y121707I141J142D01*
G01Y123218D01*
G02X1142559Y123360I200J0D01*
G03Y125490I-1059J1065D01*
G02X1142500Y125632I141J142D01*
G01Y133368D01*
G02X1142559Y133510I200J0D01*
G03Y135640I-1059J1065D01*
G02X1142500Y135782I141J142D01*
G01Y157089D01*
G02X1142559Y157231I200J0D01*
G01X1144269Y158941D01*
G02X1144411Y159000I142J-141D01*
G01X1160500D01*
G03X1161914Y159586I0J1999D01*
G01X1167114Y164786D01*
G03X1167700Y166200I-1413J1414D01*
G01Y176810D01*
G02X1167884Y177010I200J0D01*
G03X1171102Y180500I-283J3490D01*
G03X1170547Y182392I-3502J0D01*
G02Y182608I168J108D01*
G03X1171102Y184500I-2947J1892D01*
G03X1170197Y186850I-3502J1D01*
G01X1170168Y186881D01*
X1170142Y186961D01*
X1170178Y187339D01*
X1170219Y187412D01*
X1170253Y187438D01*
G03X1170452Y187837I-301J399D01*
G01Y198772D01*
G03X1169952Y199272I-500J0D01*
G01X1167900D01*
G02X1167700Y199472I0J200D01*
G01Y199666D01*
G03X1167114Y201080I-1999J0D01*
G01X1152448Y215746D01*
G03X1151034Y216332I-1414J-1413D01*
G01X1111256D01*
G02X1111114Y216391I0J200D01*
G01X1098244Y229261D01*
G02Y229543I142J141D01*
G01X1101748Y233047D01*
G02X1101890Y233106I142J-141D01*
G01X1175296D01*
G03X1176710Y233692I0J1999D01*
G01X1181585Y238567D01*
G03X1182171Y239981I-1413J1414D01*
G01Y285994D01*
G02X1182230Y286136I200J0D01*
G01X1183835Y287741D01*
G02X1183977Y287800I142J-141D01*
G01X1206500D01*
G03X1207914Y288386I0J1999D01*
G01X1215969Y296441D01*
G02X1216111Y296500I142J-141D01*
G01X1259400D01*
G03X1260814Y297086I0J1999D01*
G01X1264914Y301186D01*
G03X1265500Y302600I-1413J1414D01*
G01Y476000D01*
G03X1264914Y477414I-1999J0D01*
G01X1259814Y482514D01*
G03X1258400Y483100I-1414J-1413D01*
G01X1196911D01*
G02X1196769Y483159I0J200D01*
G01X1182230Y497698D01*
G02X1182171Y497840I141J142D01*
G01Y518623D01*
G03X1181585Y520037I-1999J0D01*
G01X1176743Y524879D01*
G03X1175329Y525465I-1414J-1413D01*
G01X1101564D01*
G02X1101422Y525524I0J200D01*
G01X1097334Y529612D01*
G02X1097275Y529754I141J142D01*
G01Y571956D01*
G02X1097334Y572098I200J0D01*
G01X1099641Y574405D01*
X1099767Y574425D01*
X1099826Y574396D01*
G03X1100498Y574237I673J1343D01*
G03X1101564Y574681I0J1502D01*
G02X1101706Y574740I142J-141D01*
G01X1119290D01*
G02X1119432Y574681I0J-200D01*
G03X1121564I1066J1058D01*
G02X1121706Y574740I142J-141D01*
G01X1139290D01*
G02X1139432Y574681I0J-200D01*
G03X1141564I1066J1058D01*
G02X1141706Y574740I142J-141D01*
G01X1159290D01*
G02X1159432Y574681I0J-200D01*
G03X1161564I1066J1058D01*
G02X1161706Y574740I142J-141D01*
G01X1179290D01*
G02X1179432Y574681I0J-200D01*
G03X1181564I1066J1058D01*
G02X1181706Y574740I142J-141D01*
G01X1199290D01*
G02X1199432Y574681I0J-200D01*
G03X1201564I1066J1058D01*
G02X1201706Y574740I142J-141D01*
G01X1219290D01*
G02X1219432Y574681I0J-200D01*
G03X1221564I1066J1058D01*
G02X1221706Y574740I142J-141D01*
G01X1239290D01*
G02X1239432Y574681I0J-200D01*
G03X1241564I1066J1058D01*
G02X1241706Y574740I142J-141D01*
G01X1259290D01*
G02X1259432Y574681I0J-200D01*
G03X1261564I1066J1058D01*
G02X1261706Y574740I142J-141D01*
G37*
G36*
G01X64877Y466181D02*
X134720D01*
G02X134862Y466122I0J-200D01*
G01X137751Y463233D01*
G02X137810Y463091I-141J-142D01*
G01Y333790D01*
G03X138396Y332376I1999J0D01*
G01X144186Y326586D01*
G03X145600Y326000I1414J1413D01*
G01X158323D01*
G02X158503Y325888I0J-200D01*
G01X158686Y325513D01*
X158674Y325400D01*
X158638Y325354D01*
G03X157898Y323200I2762J-2153D01*
G03X164902I3502J0D01*
G03X164162Y325354I-3502J1D01*
G01X164126Y325400D01*
X164114Y325513D01*
X164297Y325888D01*
G02X164477Y326000I180J-88D01*
G01X174686D01*
G02X174828Y325941I0J-200D01*
G01X176537Y324232D01*
G02X176596Y324090I-141J-142D01*
G01Y323125D01*
G02X176537Y322983I-200J0D01*
G01X149586Y296032D01*
G03X149000Y294618I1413J-1414D01*
G01Y270411D01*
G02X148941Y270269I-200J0D01*
G01X146831Y268159D01*
G02X146689Y268100I-142J141D01*
G01X36811D01*
G02X36669Y268159I0J200D01*
G01X34159Y270669D01*
G02X34100Y270811I141J142D01*
G01Y302989D01*
G02X34159Y303131I200J0D01*
G01X35869Y304841D01*
G02X36011Y304900I142J-141D01*
G01X58900D01*
G03X60314Y305486I0J1999D01*
G01X61414Y306586D01*
G03X62000Y308000I-1413J1414D01*
G01Y463304D01*
G02X62059Y463446I200J0D01*
G01X64735Y466122D01*
G02X64877Y466181I142J-141D01*
G37*
G36*
G01X208072Y262102D02*
G03X211722Y263639I0J5102D01*
G02X211866Y263700I144J-139D01*
G01X212150D01*
G02X212294Y263639I0J-200D01*
G03X215944Y262102I3650J3565D01*
G01X215946D01*
G03X219596Y263639I0J5102D01*
G02X219740Y263700I144J-139D01*
G01X220024D01*
G02X220168Y263639I0J-200D01*
G03X223818Y262102I3650J3565D01*
G01X223820D01*
G03X227470Y263639I0J5102D01*
G02X227614Y263700I144J-139D01*
G01X227898D01*
G02X228042Y263639I0J-200D01*
G03X231692Y262102I3650J3565D01*
G01X231694D01*
G03X235344Y263639I0J5102D01*
G02X235488Y263700I144J-139D01*
G01X235772D01*
G02X235916Y263639I0J-200D01*
G03X239566Y262102I3650J3565D01*
G01X239568D01*
G03X243218Y263639I0J5102D01*
G02X243362Y263700I144J-139D01*
G01X243646D01*
G02X243790Y263639I0J-200D01*
G03X247439Y262102I3650J3565D01*
G01X247441D01*
G03Y272306I0J5102D01*
G01X247439D01*
G03X243790Y270769I1J-5102D01*
G02X243646Y270708I-144J139D01*
G01X243362D01*
G02X243218Y270769I0J200D01*
G03X239568Y272306I-3650J-3565D01*
G01X239566D01*
G03X235916Y270769I0J-5102D01*
G02X235772Y270708I-144J139D01*
G01X235488D01*
G02X235344Y270769I0J200D01*
G03X231694Y272306I-3650J-3565D01*
G01X231692D01*
G03X228042Y270769I0J-5102D01*
G02X227898Y270708I-144J139D01*
G01X227614D01*
G02X227470Y270769I0J200D01*
G03X223820Y272306I-3650J-3565D01*
G01X223818D01*
G03X220168Y270769I0J-5102D01*
G02X220024Y270708I-144J139D01*
G01X219740D01*
G02X219596Y270769I0J200D01*
G03X215946Y272306I-3650J-3565D01*
G01X215944D01*
G03X212294Y270769I0J-5102D01*
G02X212150Y270708I-144J139D01*
G01X211866D01*
G02X211722Y270769I0J200D01*
G03X208072Y272306I-3650J-3565D01*
G01X208070D01*
G03X204420Y270769I0J-5102D01*
G02X204276Y270708I-144J139D01*
G01X203992D01*
G02X203848Y270769I0J200D01*
G03X202095Y271940I-3650J-3566D01*
G01X202048Y271959D01*
X201984Y272036D01*
X201907Y272413D01*
G02X201961Y272594I196J40D01*
G01X221926Y292559D01*
G02X222068Y292618I142J-141D01*
G01X308050D01*
G02X308192Y292559I0J-200D01*
G01X332665Y268086D01*
G03X334079Y267500I1414J1413D01*
G01X352175D01*
G02X352315Y267443I0J-200D01*
G01X352515Y267247D01*
G02X352575Y267109I-140J-143D01*
G01Y267108D01*
G03X357677Y262102I5102J97D01*
G01X357679D01*
G03X361328Y263639I-1J5102D01*
G02X361472Y263700I144J-139D01*
G01X361756D01*
G02X361900Y263639I0J-200D01*
G03X365550Y262102I3650J3565D01*
G01X365552D01*
G03X369202Y263639I0J5102D01*
G02X369346Y263700I144J-139D01*
G01X369630D01*
G02X369774Y263639I0J-200D01*
G03X373424Y262102I3650J3565D01*
G01X373426D01*
G03X377076Y263639I0J5102D01*
G02X377220Y263700I144J-139D01*
G01X377504D01*
G02X377648Y263639I0J-200D01*
G03X381298Y262102I3650J3565D01*
G01X381300D01*
G03X384950Y263639I0J5102D01*
G02X385094Y263700I144J-139D01*
G01X385378D01*
G02X385522Y263639I0J-200D01*
G03X389172Y262102I3650J3565D01*
G01X389174D01*
G03X392824Y263639I0J5102D01*
G02X392968Y263700I144J-139D01*
G01X393252D01*
G02X393396Y263639I0J-200D01*
G03X397046Y262102I3650J3565D01*
G01X397048D01*
G03X400698Y263639I0J5102D01*
G02X400842Y263700I144J-139D01*
G01X401126D01*
G02X401270Y263639I0J-200D01*
G03X404919Y262102I3650J3565D01*
G01X404921D01*
G03Y272306I0J5102D01*
G01X404919D01*
G03X401270Y270769I1J-5102D01*
G02X401126Y270708I-144J139D01*
G01X400842D01*
G02X400698Y270769I0J200D01*
G03X397048Y272306I-3650J-3565D01*
G01X397046D01*
G03X393396Y270769I0J-5102D01*
G02X393252Y270708I-144J139D01*
G01X392968D01*
G02X392824Y270769I0J200D01*
G03X389174Y272306I-3650J-3565D01*
G01X389172D01*
G03X385522Y270769I0J-5102D01*
G02X385378Y270708I-144J139D01*
G01X385094D01*
G02X384950Y270769I0J200D01*
G03X381300Y272306I-3650J-3565D01*
G01X381298D01*
G03X377648Y270769I0J-5102D01*
G02X377504Y270708I-144J139D01*
G01X377220D01*
G02X377076Y270769I0J200D01*
G03X373426Y272306I-3650J-3565D01*
G01X373424D01*
G03X369774Y270769I0J-5102D01*
G02X369630Y270708I-144J139D01*
G01X369346D01*
G02X369202Y270769I0J200D01*
G03X365552Y272306I-3650J-3565D01*
G01X365550D01*
G03X361900Y270769I0J-5102D01*
G02X361756Y270708I-144J139D01*
G01X361472D01*
G02X361328Y270769I0J200D01*
G03X359575Y271940I-3650J-3566D01*
G01X359528Y271959D01*
X359464Y272036D01*
X359387Y272413D01*
G02X359441Y272594I196J40D01*
G01X379406Y292559D01*
G02X379548Y292618I142J-141D01*
G01X465531D01*
G02X465673Y292559I0J-200D01*
G01X490146Y268086D01*
G03X491560Y267500I1414J1413D01*
G01X509656D01*
G02X509796Y267443I0J-200D01*
G01X509996Y267247D01*
G02X510056Y267109I-140J-143D01*
G01Y267108D01*
G03X515158Y262102I5102J97D01*
G01X515160D01*
G03X518809Y263639I-1J5102D01*
G02X518953Y263700I144J-139D01*
G01X519237D01*
G02X519381Y263639I0J-200D01*
G03X523031Y262102I3650J3565D01*
G01X523033D01*
G03X526683Y263639I0J5102D01*
G02X526827Y263700I144J-139D01*
G01X527111D01*
G02X527255Y263639I0J-200D01*
G03X530905Y262102I3650J3565D01*
G01X530907D01*
G03X534557Y263639I0J5102D01*
G02X534701Y263700I144J-139D01*
G01X534985D01*
G02X535129Y263639I0J-200D01*
G03X538779Y262102I3650J3565D01*
G01X538781D01*
G03X542431Y263639I0J5102D01*
G02X542575Y263700I144J-139D01*
G01X542859D01*
G02X543003Y263639I0J-200D01*
G03X546653Y262102I3650J3565D01*
G01X546655D01*
G03X550305Y263639I0J5102D01*
G02X550449Y263700I144J-139D01*
G01X550733D01*
G02X550877Y263639I0J-200D01*
G03X554527Y262102I3650J3565D01*
G01X554529D01*
G03X558179Y263639I0J5102D01*
G02X558323Y263700I144J-139D01*
G01X558607D01*
G02X558751Y263639I0J-200D01*
G03X562400Y262102I3650J3565D01*
G01X562402D01*
G03Y272306I0J5102D01*
G01X562400D01*
G03X558751Y270769I1J-5102D01*
G02X558607Y270708I-144J139D01*
G01X558323D01*
G02X558179Y270769I0J200D01*
G03X554529Y272306I-3650J-3565D01*
G01X554527D01*
G03X550877Y270769I0J-5102D01*
G02X550733Y270708I-144J139D01*
G01X550449D01*
G02X550305Y270769I0J200D01*
G03X546655Y272306I-3650J-3565D01*
G01X546653D01*
G03X543003Y270769I0J-5102D01*
G02X542859Y270708I-144J139D01*
G01X542575D01*
G02X542431Y270769I0J200D01*
G03X538781Y272306I-3650J-3565D01*
G01X538779D01*
G03X535129Y270769I0J-5102D01*
G02X534985Y270708I-144J139D01*
G01X534701D01*
G02X534557Y270769I0J200D01*
G03X530907Y272306I-3650J-3565D01*
G01X530905D01*
G03X527255Y270769I0J-5102D01*
G02X527111Y270708I-144J139D01*
G01X526827D01*
G02X526683Y270769I0J200D01*
G03X523033Y272306I-3650J-3565D01*
G01X523031D01*
G03X519381Y270769I0J-5102D01*
G02X519237Y270708I-144J139D01*
G01X518953D01*
G02X518809Y270769I0J200D01*
G03X517056Y271940I-3650J-3566D01*
G01X517009Y271959D01*
X516945Y272036D01*
X516868Y272413D01*
G02X516922Y272594I196J40D01*
G01X536887Y292559D01*
G02X537029Y292618I142J-141D01*
G01X623012D01*
G02X623154Y292559I0J-200D01*
G01X647627Y268086D01*
G03X649041Y267500I1414J1413D01*
G01X667137D01*
G02X667277Y267443I0J-200D01*
G01X667477Y267247D01*
G02X667537Y267109I-140J-143D01*
G01Y267108D01*
G03X672639Y262102I5102J97D01*
G01X672641D01*
G03X676290Y263639I-1J5102D01*
G02X676434Y263700I144J-139D01*
G01X676718D01*
G02X676862Y263639I0J-200D01*
G03X680512Y262102I3650J3565D01*
G01X680514D01*
G03X684164Y263639I0J5102D01*
G02X684308Y263700I144J-139D01*
G01X684592D01*
G02X684736Y263639I0J-200D01*
G03X688386Y262102I3650J3565D01*
G01X688388D01*
G03X692038Y263639I0J5102D01*
G02X692182Y263700I144J-139D01*
G01X692466D01*
G02X692610Y263639I0J-200D01*
G03X696260Y262102I3650J3565D01*
G01X696262D01*
G03X699912Y263639I0J5102D01*
G02X700056Y263700I144J-139D01*
G01X700340D01*
G02X700484Y263639I0J-200D01*
G03X704134Y262102I3650J3565D01*
G01X704136D01*
G03X707786Y263639I0J5102D01*
G02X707930Y263700I144J-139D01*
G01X708214D01*
G02X708358Y263639I0J-200D01*
G03X712008Y262102I3650J3565D01*
G01X712010D01*
G03X715660Y263639I0J5102D01*
G02X715804Y263700I144J-139D01*
G01X716088D01*
G02X716232Y263639I0J-200D01*
G03X719881Y262102I3650J3565D01*
G01X719883D01*
G03Y272306I0J5102D01*
G01X719881D01*
G03X716232Y270769I1J-5102D01*
G02X716088Y270708I-144J139D01*
G01X715804D01*
G02X715660Y270769I0J200D01*
G03X712010Y272306I-3650J-3565D01*
G01X712008D01*
G03X708358Y270769I0J-5102D01*
G02X708214Y270708I-144J139D01*
G01X707930D01*
G02X707786Y270769I0J200D01*
G03X704136Y272306I-3650J-3565D01*
G01X704134D01*
G03X700484Y270769I0J-5102D01*
G02X700340Y270708I-144J139D01*
G01X700056D01*
G02X699912Y270769I0J200D01*
G03X696262Y272306I-3650J-3565D01*
G01X696260D01*
G03X692610Y270769I0J-5102D01*
G02X692466Y270708I-144J139D01*
G01X692182D01*
G02X692038Y270769I0J200D01*
G03X688388Y272306I-3650J-3565D01*
G01X688386D01*
G03X684736Y270769I0J-5102D01*
G02X684592Y270708I-144J139D01*
G01X684308D01*
G02X684164Y270769I0J200D01*
G03X680514Y272306I-3650J-3565D01*
G01X680512D01*
G03X676862Y270769I0J-5102D01*
G02X676718Y270708I-144J139D01*
G01X676434D01*
G02X676290Y270769I0J200D01*
G03X674537Y271940I-3650J-3566D01*
G01X674490Y271959D01*
X674426Y272036D01*
X674349Y272413D01*
G02X674403Y272594I196J40D01*
G01X693780Y291971D01*
G02X693948Y292028I142J-141D01*
G03X694405Y291998I457J3472D01*
G01X694406D01*
G03X696346Y292585I-1J3502D01*
G02X696456Y292618I110J-167D01*
G01X720939D01*
G02X721105Y292530I0J-200D01*
G03X726895I2895J1969D01*
G02X727061Y292618I166J-112D01*
G01X802710D01*
G02X802852Y292559I0J-200D01*
G01X822969Y272442D01*
X822987Y272310D01*
X822953Y272251D01*
G03X822498Y270525I3046J-1726D01*
G03X826000Y267023I3502J0D01*
G01X826001D01*
G03X827726Y267478I-1J3501D01*
G02X827966Y267445I98J-174D01*
G01X830761Y264650D01*
G02X830809Y264444I-141J-142D01*
G01X830694Y264105D01*
G02X830532Y263971I-190J64D01*
G01X830531D01*
G03X828704Y263145I469J-3471D01*
G01X828676Y263121D01*
X828608Y263095D01*
X828417Y263097D01*
X828351Y263122D01*
X828323Y263147D01*
G03X826000Y264028I-2323J-2622D01*
G03Y257022I0J-3503D01*
G03X828296Y257880I-1J3503D01*
G01X828324Y257904D01*
X828392Y257930D01*
X828583Y257928D01*
X828649Y257903D01*
X828677Y257878D01*
G03X830998Y256998I2322J2622D01*
G01X831000D01*
G03X833310Y257867I1J3503D01*
G01X833337Y257891D01*
X833405Y257917D01*
X833595D01*
X833663Y257891D01*
X833690Y257867D01*
G03X836000Y256998I2309J2634D01*
G01X836001D01*
G03X837741Y257461I0J3502D01*
G02X837982Y257429I100J-173D01*
G01X841053Y254358D01*
G02X841112Y254216I-141J-142D01*
G01Y188642D01*
G02X841053Y188500I-200J0D01*
G01X836233Y183680D01*
G02X836091Y183621I-142J141D01*
G01X807563D01*
G03X806149Y183035I0J-1999D01*
G01X802586Y179472D01*
G03X802000Y178058I1413J-1414D01*
G01Y101911D01*
G02X801941Y101769I-200J0D01*
G01X796042Y95870D01*
G02X795900Y95811I-142J141D01*
G01X227411D01*
G02X227269Y95870I0J200D01*
G01X139559Y183580D01*
G02X139500Y183722I141J142D01*
G01Y224089D01*
G02X139559Y224231I200J0D01*
G01X152755Y237427D01*
G02X153018Y237445I142J-141D01*
G03X155140Y236728I2123J2785D01*
G03X158642Y240230I0J3502D01*
G03X157854Y242444I-3504J0D01*
G02X157828Y242658I154J127D01*
G03X158001Y243202I-1799J872D01*
G02X158017Y243254I197J-32D01*
G03X158342Y244728I-3178J1473D01*
G01Y244731D01*
G03X158044Y246145I-3502J0D01*
G02X158027Y246226I183J81D01*
G01Y267300D01*
G02X158227Y267500I200J0D01*
G01X194695D01*
G02X194835Y267443I0J-200D01*
G01X195035Y267247D01*
G02X195095Y267109I-140J-143D01*
G01Y267108D01*
G03X200197Y262102I5102J97D01*
G01X200199D01*
G03X203848Y263639I-1J5102D01*
G02X203992Y263700I144J-139D01*
G01X204276D01*
G02X204420Y263639I0J-200D01*
G03X208070Y262102I3650J3565D01*
G01X208072D01*
G37*
G36*
G01X931500Y362498D02*
G03X931726Y362505I5J3502D01*
G01X931727D01*
G02X931894Y362432I12J-200D01*
G01X932131Y362141D01*
X932151Y362047D01*
X932138Y362000D01*
G03X932014Y361078I3378J-924D01*
G01Y361075D01*
G03X939018I3502J0D01*
G01Y361079D01*
G03X938747Y362428I-3502J-2D01*
G02X938798Y362654I184J77D01*
G01X939078Y362907D01*
G02X939309Y362933I134J-149D01*
G03X941000Y362498I1690J3067D01*
G03X942419Y362798I1J3502D01*
G02X942581I81J-183D01*
G03X944000Y362498I1418J3202D01*
G03X946917Y364061I1J3502D01*
G01X946945Y364102D01*
X947033Y364150D01*
X947467D01*
X947555Y364102D01*
X947583Y364061D01*
G03X950500Y362498I2916J1939D01*
G03X951919Y362798I1J3502D01*
G02X952081I81J-183D01*
G03X953498Y362498I1418J3202D01*
G01X953500D01*
G03Y369502I0J3502D01*
G01X953498D01*
G03X952081Y369202I1J-3502D01*
G02X951919I-81J183D01*
G03X950500Y369502I-1418J-3202D01*
G03X947583Y367939I-1J-3502D01*
G01X947555Y367898D01*
X947467Y367850D01*
X947033D01*
X946945Y367898D01*
X946917Y367939D01*
G03X944000Y369502I-2916J-1939D01*
G03X942581Y369202I-1J-3502D01*
G02X942419I-81J183D01*
G03X941000Y369502I-1418J-3202D01*
G03X938083Y367939I-1J-3502D01*
G01X938055Y367898D01*
X937967Y367850D01*
X937533D01*
X937445Y367898D01*
X937417Y367939D01*
G03X934500Y369502I-2916J-1939D01*
G03X933081Y369202I-1J-3502D01*
G02X932919I-81J183D01*
G03X931500Y369502I-1418J-3202D01*
G03X928583Y367939I-1J-3502D01*
G01X928555Y367898D01*
X928467Y367850D01*
X928033D01*
X927945Y367898D01*
X927917Y367939D01*
G03X925000Y369502I-2916J-1939D01*
G03X923581Y369202I-1J-3502D01*
G02X923419I-81J183D01*
G03X922000Y369502I-1418J-3202D01*
G03X919083Y367939I-1J-3502D01*
G01X919055Y367898D01*
X918967Y367850D01*
X918533D01*
X918445Y367898D01*
X918417Y367939D01*
G03X915500Y369502I-2916J-1939D01*
G03X914081Y369202I-1J-3502D01*
G02X913919I-81J183D01*
G03X912500Y369502I-1418J-3202D01*
G03X909583Y367939I-1J-3502D01*
G01X909555Y367898D01*
X909467Y367850D01*
X909033D01*
X908945Y367898D01*
X908917Y367939D01*
G03X906000Y369502I-2916J-1939D01*
G03X904581Y369202I-1J-3502D01*
G02X904419I-81J183D01*
G03X903000Y369502I-1418J-3202D01*
G03X900083Y367939I-1J-3502D01*
G01X900055Y367898D01*
X899967Y367850D01*
X899533D01*
X899445Y367898D01*
X899417Y367939D01*
G03X896500Y369502I-2916J-1939D01*
G03X895081Y369202I-1J-3502D01*
G02X894919I-81J183D01*
G03X893500Y369502I-1418J-3202D01*
G03X890583Y367939I-1J-3502D01*
G01X890555Y367898D01*
X890467Y367850D01*
X890033D01*
X889945Y367898D01*
X889917Y367939D01*
G03X887000Y369502I-2916J-1939D01*
G03X885581Y369202I-1J-3502D01*
G02X885419I-81J183D01*
G03X884000Y369502I-1418J-3202D01*
G03X881083Y367939I-1J-3502D01*
G01X881055Y367898D01*
X880967Y367850D01*
X880533D01*
X880445Y367898D01*
X880417Y367939D01*
G03X877500Y369502I-2916J-1939D01*
G03X876081Y369202I-1J-3502D01*
G02X875919I-81J183D01*
G03X874500Y369502I-1418J-3202D01*
G03X871807Y368240I-1J-3502D01*
G01X871779Y368206D01*
X871699Y368168D01*
X871301D01*
X871221Y368206D01*
X871193Y368240D01*
G03X868500Y369502I-2692J-2240D01*
G03X867081Y369202I-1J-3502D01*
G02X866919I-81J183D01*
G03X865500Y369502I-1418J-3202D01*
G03X862807Y368240I-1J-3502D01*
G01X862779Y368206D01*
X862699Y368168D01*
X862301D01*
X862221Y368206D01*
X862193Y368240D01*
G03X859500Y369502I-2692J-2240D01*
G03X858081Y369202I-1J-3502D01*
G02X857919I-81J183D01*
G03X856500Y369502I-1418J-3202D01*
G03X853807Y368240I-1J-3502D01*
G01X853779Y368206D01*
X853699Y368168D01*
X853301D01*
X853221Y368206D01*
X853193Y368240D01*
G03X850500Y369502I-2692J-2240D01*
G03X849081Y369202I-1J-3502D01*
G02X848919I-81J183D01*
G03X847502Y369502I-1418J-3202D01*
G01X847500D01*
G03X843998Y366000I0J-3502D01*
G03X847205Y362510I3502J0D01*
G01X847257Y362506D01*
X847343Y362448D01*
X847544Y362051D01*
X847540Y361948D01*
X847513Y361903D01*
G03X847353Y361612I2985J-1831D01*
G02X847174Y361500I-180J88D01*
G01X830494D01*
G02X830305Y361634I0J200D01*
G03X823695I-3305J-1159D01*
G02X823506Y361500I-189J66D01*
G01X817876D01*
G02X817733Y361560I0J200D01*
G01X817504Y361795D01*
X817475Y361869D01*
X817476Y361910D01*
G03X817478Y361999I-3500J123D01*
G01Y362001D01*
G03X810472I-3503J-1D01*
G01Y361999D01*
G03X810474Y361911I3502J36D01*
G01Y361909D01*
X810475Y361869D01*
X810446Y361795D01*
X810217Y361560D01*
G02X810074Y361500I-143J140D01*
G01X806876D01*
G02X806733Y361560I0J200D01*
G01X806504Y361795D01*
X806475Y361869D01*
X806476Y361910D01*
G03X806478Y361999I-3500J123D01*
G01Y362001D01*
G03X799472I-3503J-1D01*
G01Y361999D01*
G03X799474Y361911I3502J36D01*
G01Y361909D01*
X799475Y361869D01*
X799446Y361795D01*
X799217Y361560D01*
G02X799074Y361500I-143J140D01*
G01X792118D01*
X792112D01*
G03X792000Y361502I-119J-3500D01*
G03X791888Y361500I7J-3502D01*
G01X785319D01*
G02X785164Y361574I0J200D01*
G01X784968Y361816D01*
G02X784928Y361982I156J125D01*
G03X785002Y362696I-3428J716D01*
G01Y362700D01*
G03X777998I-3502J0D01*
G01Y362696D01*
G03X778072Y361982I3502J2D01*
G02X778032Y361816I-196J-41D01*
G01X777836Y361574D01*
G02X777681Y361500I-155J126D01*
G01X746197D01*
G02X745997Y361688I0J200D01*
G01Y361689D01*
G03X739003I-3497J-189D01*
G01Y361688D01*
G02X738803Y361500I-200J12D01*
G01X709986D01*
G02X709865Y361541I0J200D01*
G03X707750Y362252I-2115J-2790D01*
G03X706025Y361798I-1J-3501D01*
G02X705844Y361790I-98J174D01*
G03X704400Y362102I-1445J-3190D01*
G03X702486Y361533I-1J-3502D01*
G02X702377Y361500I-110J167D01*
G01X618500D01*
G03X617086Y360914I0J-1999D01*
G01X586231Y330059D01*
G02X586089Y330000I-142J141D01*
G01X146511D01*
G02X146369Y330059I0J200D01*
G01X141869Y334559D01*
G02X141810Y334701I141J142D01*
G01Y463091D01*
G02X141869Y463233I200J0D01*
G01X144758Y466122D01*
G02X144900Y466181I142J-141D01*
G01X874643D01*
G03X876057Y466767I0J1999D01*
G01X880377Y471087D01*
G03X880963Y472501I-1413J1414D01*
G01Y549905D01*
G02X881086Y550089I200J0D01*
G03Y567151I-3576J8531D01*
G02X880963Y567335I77J184D01*
G01Y570833D01*
G02X881022Y570975I200J0D01*
G01X884728Y574681D01*
G02X884870Y574740I142J-141D01*
G01X936996D01*
G02X937185Y574606I0J-200D01*
G01Y574605D01*
G03X943811I3313J1134D01*
G01Y574606D01*
G02X944000Y574740I189J-66D01*
G01X956996D01*
G02X957185Y574606I0J-200D01*
G01Y574605D01*
G03X963811I3313J1134D01*
G01Y574606D01*
G02X964000Y574740I189J-66D01*
G01X976996D01*
G02X977185Y574606I0J-200D01*
G01Y574605D01*
G03X983811I3313J1134D01*
G01Y574606D01*
G02X984000Y574740I189J-66D01*
G01X996996D01*
G02X997185Y574606I0J-200D01*
G01Y574605D01*
G03X1003811I3313J1134D01*
G01Y574606D01*
G02X1004000Y574740I189J-66D01*
G01X1016996D01*
G02X1017185Y574606I0J-200D01*
G01Y574605D01*
G03X1023811I3313J1134D01*
G01Y574606D01*
G02X1024000Y574740I189J-66D01*
G01X1036996D01*
G02X1037185Y574606I0J-200D01*
G01Y574605D01*
G03X1043811I3313J1134D01*
G01Y574606D01*
G02X1044000Y574740I189J-66D01*
G01X1056996D01*
G02X1057185Y574606I0J-200D01*
G01Y574605D01*
G03X1063811I3313J1134D01*
G01Y574606D01*
G02X1064000Y574740I189J-66D01*
G01X1076996D01*
G02X1077185Y574606I0J-200D01*
G01Y574605D01*
G03X1083811I3313J1134D01*
G01Y574606D01*
G02X1084000Y574740I189J-66D01*
G01X1090491D01*
G02X1090633Y574681I0J-200D01*
G01X1093216Y572098D01*
G02X1093275Y571956I-141J-142D01*
G01Y529754D01*
G02X1093216Y529612I-200J0D01*
G01X1089128Y525524D01*
G02X1088986Y525465I-142J141D01*
G01X1060965D01*
G03X1059551Y524879I0J-1999D01*
G01X1056386Y521714D01*
G03X1055800Y520300I1413J-1414D01*
G01Y504000D01*
G03X1056386Y502586I1999J0D01*
G01X1059286Y499686D01*
G03X1060700Y499100I1414J1413D01*
G01X1073989D01*
G02X1074131Y499041I0J-200D01*
G01X1075441Y497731D01*
G02X1075500Y497589I-141J-142D01*
G01Y478411D01*
G02X1075441Y478269I-200J0D01*
G01X1073831Y476659D01*
G02X1073689Y476600I-142J141D01*
G01X1060100D01*
G03X1058686Y476014I0J-1999D01*
G01X1056386Y473714D01*
G03X1055800Y472300I1413J-1414D01*
G01Y456700D01*
G03X1056386Y455286I1999J0D01*
G01X1058886Y452786D01*
G03X1060300Y452200I1414J1413D01*
G01X1073389D01*
G02X1073531Y452141I0J-200D01*
G01X1075441Y450231D01*
G02X1075500Y450089I-141J-142D01*
G01Y430911D01*
G02X1075441Y430769I-200J0D01*
G01X1072831Y428159D01*
G02X1072689Y428100I-142J141D01*
G01X1060600D01*
G03X1059186Y427514I0J-1999D01*
G01X1056386Y424714D01*
G03X1055800Y423300I1413J-1414D01*
G01Y416343D01*
G03X1056386Y414929I1999J0D01*
G01X1058137Y413178D01*
G03X1059551Y412592I1414J1413D01*
G01X1063870D01*
G02X1064068Y412422I0J-200D01*
G03X1067531Y409440I3463J520D01*
G03X1067862Y409456I-3J3502D01*
G01X1067905Y409460D01*
X1067983Y409434D01*
X1068234Y409206D01*
G02X1068300Y409057I-134J-148D01*
G01Y405400D01*
G03X1068886Y403986I1999J0D01*
G01X1070786Y402086D01*
G03X1072200Y401500I1414J1413D01*
G01X1074589D01*
G02X1074731Y401441I0J-200D01*
G01X1075441Y400731D01*
G02X1075500Y400589I-141J-142D01*
G01Y385911D01*
G02X1075441Y385769I-200J0D01*
G01X1073586Y383914D01*
G03X1073000Y382500I1413J-1414D01*
G01Y372861D01*
G02X1072941Y372719I-200J0D01*
G01X1072281Y372059D01*
G02X1072139Y372000I-142J141D01*
G01X1059319D01*
G03X1057905Y371414I0J-1999D01*
G01X1056386Y369895D01*
G03X1055800Y368481I1413J-1414D01*
G01Y359700D01*
G03X1056386Y358286I1999J0D01*
G01X1059586Y355086D01*
G03X1061000Y354500I1414J1413D01*
G01X1074589D01*
G02X1074731Y354441I0J-200D01*
G01X1075441Y353731D01*
G02X1075500Y353589I-141J-142D01*
G01Y338411D01*
G02X1075441Y338269I-200J0D01*
G01X1073731Y336559D01*
G02X1073589Y336500I-142J141D01*
G01X1060500D01*
G03X1059086Y335914I0J-1999D01*
G01X1056386Y333214D01*
G03X1055800Y331800I1413J-1414D01*
G01Y314700D01*
G03X1056386Y313286I1999J0D01*
G01X1059386Y310286D01*
G03X1060800Y309700I1414J1413D01*
G01X1073889D01*
G02X1074031Y309641I0J-200D01*
G01X1075441Y308231D01*
G02X1075500Y308089I-141J-142D01*
G01Y284411D01*
G02X1075441Y284269I-200J0D01*
G01X1073831Y282659D01*
G02X1073689Y282600I-142J141D01*
G01X1061100D01*
G03X1059686Y282014I0J-1999D01*
G01X1056386Y278714D01*
G03X1055800Y277300I1413J-1414D01*
G01Y264700D01*
G03X1056386Y263286I1999J0D01*
G01X1059186Y260486D01*
G03X1060600Y259900I1414J1413D01*
G01X1083627D01*
G02X1083769Y259841I0J-200D01*
G01X1084329Y259281D01*
G02X1084388Y259139I-141J-142D01*
G01Y202655D01*
G02X1084367Y202566I-200J0D01*
G03X1083998Y201000I3133J-1565D01*
G03X1084298Y199581I3502J-1D01*
G02Y199419I-183J-81D01*
G03X1083998Y198002I3202J-1418D01*
G01Y198000D01*
G03X1087500Y194498I3502J0D01*
G03X1089671Y195252I0J3502D01*
G02X1089936Y195236I123J-157D01*
G01X1102836Y182336D01*
G03X1104250Y181750I1414J1413D01*
G01X1137226D01*
G02X1137394Y181659I0J-200D01*
G03X1140334Y180058I2941J1901D01*
G01X1140336D01*
G03X1141828Y180392I-1J3503D01*
G02X1141998I85J-181D01*
G03X1143490Y180058I1493J3169D01*
G01X1143492D01*
G03X1146432Y181659I-1J3502D01*
G02X1146600Y181750I168J-109D01*
G01X1154884D01*
G02X1155063Y181639I0J-200D01*
G01X1155223Y181318D01*
G02X1155204Y181109I-179J-89D01*
G03X1154498Y179000I2797J-2109D01*
G03X1161502I3502J0D01*
G03X1160796Y181109I-3503J0D01*
G02X1160777Y181318I160J120D01*
G01X1160937Y181639D01*
G02X1161116Y181750I179J-89D01*
G01X1161539D01*
G02X1161681Y181691I0J-200D01*
G01X1163641Y179731D01*
G02X1163700Y179589I-141J-142D01*
G01Y167111D01*
G02X1163641Y166969I-200J0D01*
G01X1159731Y163059D01*
G02X1159589Y163000I-142J141D01*
G01X1155920D01*
G02X1155742Y163110I1J200D01*
G01X1155580Y163429D01*
G02X1155598Y163638I179J90D01*
G03X1156284Y165719I-2817J2082D01*
G03X1149278I-3503J0D01*
G03X1149964Y163638I3503J1D01*
G01X1149998Y163592D01*
X1150007Y163480D01*
X1149820Y163110D01*
G02X1149642Y163000I-179J90D01*
G01X1143500D01*
G03X1143116Y162962I4J-1999D01*
G02X1142911Y163047I-39J196D01*
G03X1140000Y164602I-2911J-1947D01*
G01X1139998D01*
G03X1138250Y164134I1J-3502D01*
G02X1138050I-100J173D01*
G03X1136302Y164602I-1749J-3034D01*
G01X1136300D01*
G03Y157598I0J-3502D01*
G01X1136302D01*
G03X1138050Y158066I-1J3502D01*
G02X1138250I100J-173D01*
G03X1138392Y157989I1740J3040D01*
G02X1138500Y157811I-92J-178D01*
G01Y136437D01*
G02X1138473Y136336I-200J-1D01*
G03Y132814I3028J-1761D01*
G02X1138500Y132713I-173J-100D01*
G01Y126287D01*
G02X1138473Y126186I-200J-1D01*
G03Y122664I3027J-1761D01*
G01X1138486Y122641D01*
X1138500Y122591D01*
Y122334D01*
X1138486Y122284D01*
X1138473Y122261D01*
G03X1137998Y120500I3027J-1761D01*
G01Y120498D01*
G03X1138370Y118928I3502J1D01*
G01X1138399Y118870D01*
X1138379Y118743D01*
X1138195Y118559D01*
G02X1138053Y118500I-142J141D01*
G01X1120411D01*
G02X1120269Y118559I0J200D01*
G01X1119559Y119269D01*
G02X1119500Y119411I141J142D01*
G01Y134605D01*
G02X1119570Y134757I200J0D01*
G01X1119803Y134955D01*
G02X1119963Y135000I129J-153D01*
G01X1119964D01*
G03X1120524Y134954I566J3457D01*
G03X1122118Y135338I-1J3503D01*
G01X1122119D01*
G02X1122292Y135343I92J-178D01*
G01X1122617Y135196D01*
X1122676Y135128D01*
X1122687Y135084D01*
G03X1126075Y132470I3388J889D01*
G03X1127967Y133025I0J3503D01*
G02X1128186Y133024I109J-168D01*
G03X1130125Y132438I1940J2917D01*
G03Y139442I0J3502D01*
G01X1130123D01*
G03X1128233Y138888I0J-3502D01*
G02X1128014Y138889I-109J168D01*
G03X1126075Y139476I-1941J-2915D01*
G03X1124481Y139092I1J-3503D01*
G01X1124480D01*
G02X1124307Y139087I-92J178D01*
G01X1123982Y139234D01*
X1123923Y139302D01*
X1123912Y139346D01*
G03X1123023Y140911I-3388J-889D01*
G02X1122966Y141076I142J141D01*
G01X1123004Y141385D01*
G02X1123096Y141531I199J-23D01*
G03X1124740Y144500I-1859J2969D01*
G03X1121238Y148002I-3502J0D01*
G01X1121236D01*
G03X1120037Y147790I1J-3502D01*
G01X1119991Y147773D01*
X1119894Y147786D01*
X1119585Y148002D01*
G02X1119500Y148166I115J164D01*
G01Y153109D01*
G02X1119564Y153255I200J-1D01*
G01X1119811Y153484D01*
X1119889Y153511D01*
X1119931Y153508D01*
G03X1120200Y153498I265J3492D01*
G03Y160502I0J3502D01*
G03X1117208Y158820I0J-3502D01*
G01Y158819D01*
G02X1117061Y158725I-171J105D01*
G01X1116749Y158688D01*
G02X1116583Y158745I-25J198D01*
G01X1113930Y161398D01*
G02X1113911Y161659I141J141D01*
G03X1114315Y162358I-2810J2091D01*
G02X1114425Y162465I184J-79D01*
G03X1116460Y164637I-1296J3254D01*
G02X1116628Y164774I190J-62D01*
G01X1116990Y164815D01*
G02X1117185Y164717I22J-199D01*
G03X1120199Y162998I3014J1783D01*
G01X1120200D01*
G03Y170002I0J3502D01*
G03X1116869Y167582I0J-3502D01*
G02X1116701Y167445I-190J62D01*
G01X1116339Y167404D01*
G02X1116144Y167502I-22J199D01*
G03X1115525Y168274I-3015J-1783D01*
G02X1115462Y168428I137J146D01*
G01X1115474Y168731D01*
G02X1115549Y168879I200J-8D01*
G03X1116870Y171619I-2181J2740D01*
G03X1113368Y175122I-3503J0D01*
G03X1111140Y174321I1J-3503D01*
G02X1111138Y174319I-142J140D01*
G02X1110999Y174275I-126J156D01*
G01X1110684Y174297D01*
X1110614Y174331D01*
X1110589Y174359D01*
G03X1108001Y175502I-2588J-2359D01*
G01X1108000D01*
G03X1104498Y172000I0J-3502D01*
G01Y171998D01*
G03X1105891Y169203I3502J1D01*
G02X1105968Y169075I-120J-160D01*
G01X1105987Y168956D01*
G02X1105953Y168810I-198J-31D01*
G03X1105318Y166800I2868J-2011D01*
G03X1107492Y163559I3503J0D01*
G02X1107615Y163394I-76J-185D01*
G03X1107636Y163230I3484J363D01*
G01X1107638Y163215D01*
Y163200D01*
G02X1107438Y163000I-200J0D01*
G01X1092118D01*
X1092112D01*
G03X1092000Y163002I-119J-3500D01*
G03X1091888Y163000I7J-3502D01*
G01X1089381D01*
G02X1089229Y163070I0J200D01*
G01X1089003Y163335D01*
X1088979Y163418D01*
X1088986Y163461D01*
G03X1089028Y164000I-3461J541D01*
G03X1088612Y165655I-3503J-1D01*
G02Y165845I176J95D01*
G03X1089028Y167500I-3087J1656D01*
G03X1088612Y169155I-3503J-1D01*
G02Y169345I176J95D01*
G03X1089028Y171000I-3087J1656D01*
G03X1088612Y172655I-3503J-1D01*
G02Y172845I176J95D01*
G03X1089028Y174500I-3087J1656D01*
G03X1082022I-3503J0D01*
G03X1082438Y172845I3503J1D01*
G02Y172655I-176J-95D01*
G03X1082022Y171000I3087J-1656D01*
G03X1082438Y169345I3503J1D01*
G02Y169155I-176J-95D01*
G03X1082022Y167500I3087J-1656D01*
G03X1082438Y165845I3503J1D01*
G02Y165655I-176J-95D01*
G03X1082022Y164000I3087J-1656D01*
G03X1082064Y163461I3503J2D01*
G01X1082071Y163418D01*
X1082047Y163335D01*
X1081821Y163070D01*
G02X1081669Y163000I-152J130D01*
G01X1079911D01*
G02X1079769Y163059I0J200D01*
G01X1072059Y170769D01*
G02X1072000Y170911I141J142D01*
G01Y175194D01*
G02X1072120Y175377I200J0D01*
G03Y181793I-1404J3208D01*
G02X1072000Y181976I80J183D01*
G01Y187756D01*
G02X1072080Y187916I200J0D01*
G01X1072337Y188108D01*
G02X1072513Y188140I120J-160D01*
G03X1073500Y187998I987J3359D01*
G03Y195002I0J3502D01*
G03X1072513Y194860I0J-3501D01*
G01X1072467Y194847D01*
X1072375Y194863D01*
X1072080Y195084D01*
G02X1072000Y195244I120J160D01*
G01Y198500D01*
G03X1071414Y199914I-1999J0D01*
G01X1066914Y204414D01*
G03X1065500Y205000I-1414J-1413D01*
G01X1018836D01*
G02X1018694Y205059I0J200D01*
G01X1005626Y218127D01*
X1005608Y218259D01*
X1005642Y218318D01*
G03X1008188Y228001I-17142J9683D01*
G03X988502Y247688I-19687J0D01*
G01X907563D01*
G02X907421Y247747I0J200D01*
G01X868059Y287109D01*
G02X868000Y287251I141J142D01*
G01Y287823D01*
X868074Y287926D01*
X868135Y287947D01*
G03Y294573I-1135J3313D01*
G01X868074Y294594D01*
X868000Y294697D01*
Y300965D01*
G02X868091Y301133I200J0D01*
G01X868416Y301343D01*
X868518Y301351D01*
X868564Y301330D01*
G03X870000Y301022I1436J3195D01*
G03X872310Y301892I0J3503D01*
G02X872442Y301942I132J-150D01*
G01X872558D01*
G02X872690Y301892I0J-200D01*
G03X875000Y301022I2310J2633D01*
G03X877310Y301892I0J3503D01*
G02X877442Y301942I132J-150D01*
G01X877558D01*
G02X877690Y301892I0J-200D01*
G03X880000Y301022I2310J2633D01*
G03Y308028I0J3503D01*
G03X877690Y307158I0J-3503D01*
G02X877558Y307108I-132J150D01*
G01X877442D01*
G02X877310Y307158I0J200D01*
G03X875000Y308028I-2310J-2633D01*
G03X872690Y307158I0J-3503D01*
G02X872558Y307108I-132J150D01*
G01X872442D01*
G02X872310Y307158I0J200D01*
G03X870000Y308028I-2310J-2633D01*
G03X868564Y307720I0J-3503D01*
G01X868518Y307699D01*
X868416Y307707D01*
X868091Y307917D01*
G02X868000Y308085I109J168D01*
G01Y309228D01*
G02X868091Y309396I200J0D01*
G01X868416Y309606D01*
X868518Y309614D01*
X868564Y309593D01*
G03X869996Y309286I1434J3195D01*
G01X870000D01*
G03Y316290I0J3502D01*
G01X869996D01*
G03X868564Y315983I2J-3502D01*
G01X868518Y315962D01*
X868416Y315970D01*
X868091Y316180D01*
G02X868000Y316348I109J168D01*
G01Y356644D01*
G02X868070Y356796I200J0D01*
G01X868335Y357022D01*
X868418Y357046D01*
X868461Y357039D01*
G03X869000Y356998I534J3461D01*
G03X870294Y357245I2J3502D01*
G01X870329Y357259D01*
X870407D01*
X870699Y357141D01*
G02X870806Y357038I-75J-185D01*
G03X874000Y354972I3194J1436D01*
G03X875892Y355528I-2J3503D01*
G02X876108I108J-169D01*
G03X878000Y354972I1894J2947D01*
G03X880323Y355853I0J3503D01*
G02X880454Y355904I133J-149D01*
G01X880571D01*
G02X880704Y355855I2J-200D01*
G03X882133Y355106I2297J2644D01*
G01X882177Y355095D01*
X882248Y355036D01*
X882394Y354710D01*
G02X882389Y354535I-182J-82D01*
G03X881998Y352929I3111J-1608D01*
G01Y352925D01*
G03X889002I3502J0D01*
G03X886367Y356319I-3503J0D01*
G01X886323Y356330D01*
X886252Y356389D01*
X886106Y356715D01*
G02X886111Y356890I182J82D01*
G03X886502Y358496I-3111J1608D01*
G01Y358500D01*
G03X883000Y362002I-3502J0D01*
G01X882998D01*
G03X880677Y361122I1J-3502D01*
G02X880546Y361071I-133J149D01*
G01X880429D01*
G02X880296Y361120I-2J200D01*
G03X878000Y361978I-2297J-2645D01*
G03X876108Y361422I2J-3503D01*
G02X875892I-108J169D01*
G03X874000Y361978I-1894J-2947D01*
G03X872706Y361730I1J-3503D01*
G01X872671Y361716D01*
X872593D01*
X872301Y361834D01*
G02X872194Y361937I75J185D01*
G03X871240Y363192I-3194J-1438D01*
G01X871209Y363218D01*
X871173Y363287D01*
X871144Y363610D01*
G02X871189Y363756I199J19D01*
G03X871193Y363760I-2464J2468D01*
G01X871221Y363794D01*
X871301Y363832D01*
X871699D01*
X871779Y363794D01*
X871807Y363760D01*
G03X874500Y362498I2692J2240D01*
G03X875919Y362798I1J3502D01*
G02X876081I81J-183D01*
G03X877500Y362498I1418J3202D01*
G03X880417Y364061I1J3502D01*
G01X880445Y364102D01*
X880533Y364150D01*
X880967D01*
X881055Y364102D01*
X881083Y364061D01*
G03X884000Y362498I2916J1939D01*
G03X885419Y362798I1J3502D01*
G02X885581I81J-183D01*
G03X887000Y362498I1418J3202D01*
G03X889917Y364061I1J3502D01*
G01X889945Y364102D01*
X890033Y364150D01*
X890467D01*
X890555Y364102D01*
X890583Y364061D01*
G03X893500Y362498I2916J1939D01*
G03X894919Y362798I1J3502D01*
G02X895081I81J-183D01*
G03X896500Y362498I1418J3202D01*
G03X899417Y364061I1J3502D01*
G01X899445Y364102D01*
X899533Y364150D01*
X899967D01*
X900055Y364102D01*
X900083Y364061D01*
G03X903000Y362498I2916J1939D01*
G03X904419Y362798I1J3502D01*
G02X904581I81J-183D01*
G03X906000Y362498I1418J3202D01*
G03X907160Y362695I2J3502D01*
G01X907215Y362715D01*
X907326Y362690D01*
X907623Y362397D01*
G02X907672Y362191I-141J-142D01*
G01Y362190D01*
G03X907490Y361076I3320J-1114D01*
G01Y361075D01*
G03X914494I3502J0D01*
G01Y361078D01*
G03X914353Y362060I-3502J-2D01*
G01Y362061D01*
G02X914397Y362252I192J56D01*
G01X914664Y362543D01*
X914764Y362575D01*
X914815Y362565D01*
G03X915500Y362498I682J3435D01*
G03X918417Y364061I1J3502D01*
G01X918445Y364102D01*
X918533Y364150D01*
X918967D01*
X919055Y364102D01*
X919083Y364061D01*
G03X922000Y362498I2916J1939D01*
G03X923419Y362798I1J3502D01*
G02X923581I81J-183D01*
G03X923612Y362784I1457J3185D01*
G02X923718Y362676I-79J-184D01*
G01X923764Y362564D01*
G02X923763Y362413I-186J-74D01*
G03X923498Y361076I3237J-1336D01*
G01Y361075D01*
G03X923831Y359585I3503J1D01*
G02Y359415I-181J-85D01*
G03X923498Y357925I3170J-1491D01*
G01Y357901D01*
G02X923363Y357710I-200J-2D01*
G01X923004Y357587D01*
G02X922780Y357654I-65J189D01*
G01Y357655D01*
G03X920000Y359028I-2781J-2130D01*
G03X917812Y358260I0J-3501D01*
G02X917610Y358232I-125J157D01*
G03X916264Y358502I-1348J-3232D01*
G01X916260D01*
G03Y351498I0J-3502D01*
G01X916262D01*
G03X918448Y352265I-1J3502D01*
G02X918650Y352293I125J-157D01*
G03X920000Y352022I1351J3232D01*
G03X923502Y355525I0J3502D01*
G01Y355549D01*
G02X923637Y355740I200J2D01*
G01X923996Y355863D01*
G02X924220Y355796I65J-189D01*
G01Y355795D01*
G03X927000Y354422I2781J2130D01*
G03X930502Y357923I0J3502D01*
G01Y357925D01*
G03X930169Y359415I-3503J-1D01*
G02Y359585I181J85D01*
G03X930502Y361075I-3170J1491D01*
G01Y361076D01*
G03X930361Y362059I-3502J-1D01*
G01X930346Y362110D01*
X930370Y362211D01*
X930637Y362503D01*
G02X930822Y362564I147J-135D01*
G01X930823D01*
G03X931500Y362498I677J3436D01*
G37*
G36*
G01X876904Y473270D02*
X873874Y470240D01*
G02X873732Y470181I-142J141D01*
G01X699891D01*
G02X699697Y470331I0J200D01*
G01X699601Y470706D01*
G02X699698Y470932I194J51D01*
G01X699699D01*
G03X703414Y477204I-3437J6272D01*
G03X689108I-7153J0D01*
G03X692823Y470932I7152J0D01*
G01X692824D01*
G02X692921Y470706I-97J-175D01*
G01X692825Y470331D01*
G02X692631Y470181I-194J50D01*
G01X669891D01*
G02X669697Y470331I0J200D01*
G01X669601Y470706D01*
G02X669698Y470932I194J51D01*
G01X669699D01*
G03X673414Y477204I-3437J6272D01*
G03X659108I-7153J0D01*
G03X662823Y470932I7152J0D01*
G01X662824D01*
G02X662921Y470706I-97J-175D01*
G01X662825Y470331D01*
G02X662631Y470181I-194J50D01*
G01X542410D01*
G02X542216Y470331I0J200D01*
G01X542120Y470706D01*
G02X542217Y470932I194J51D01*
G01X542218D01*
G03X545932Y477204I-3439J6272D01*
G03X531628I-7152J0D01*
G03X535342Y470932I7153J0D01*
G01X535343D01*
G02X535440Y470706I-97J-175D01*
G01X535344Y470331D01*
G02X535150Y470181I-194J50D01*
G01X512410D01*
G02X512216Y470331I0J200D01*
G01X512120Y470706D01*
G02X512217Y470932I194J51D01*
G01X512218D01*
G03X515932Y477204I-3439J6272D01*
G03X501628I-7152J0D01*
G03X505342Y470932I7153J0D01*
G01X505343D01*
G02X505440Y470706I-97J-175D01*
G01X505344Y470331D01*
G02X505150Y470181I-194J50D01*
G01X384929D01*
G02X384735Y470331I0J200D01*
G01X384639Y470706D01*
G02X384736Y470932I194J51D01*
G01X384737D01*
G03X388452Y477204I-3437J6272D01*
G03X374146I-7153J0D01*
G03X377861Y470932I7152J0D01*
G01X377862D01*
G02X377959Y470706I-97J-175D01*
G01X377863Y470331D01*
G02X377669Y470181I-194J50D01*
G01X354929D01*
G02X354735Y470331I0J200D01*
G01X354639Y470706D01*
G02X354736Y470932I194J51D01*
G01X354737D01*
G03X358452Y477204I-3437J6272D01*
G03X344146I-7153J0D01*
G03X347861Y470932I7152J0D01*
G01X347862D01*
G02X347959Y470706I-97J-175D01*
G01X347863Y470331D01*
G02X347669Y470181I-194J50D01*
G01X227449D01*
G02X227255Y470331I0J200D01*
G01X227159Y470706D01*
G02X227256Y470932I194J51D01*
G01X227257D01*
G03X230972Y477204I-3437J6272D01*
G03X216666I-7153J0D01*
G03X220381Y470932I7152J0D01*
G01X220382D01*
G02X220479Y470706I-97J-175D01*
G01X220383Y470331D01*
G02X220189Y470181I-194J50D01*
G01X197449D01*
G02X197255Y470331I0J200D01*
G01X197159Y470706D01*
G02X197256Y470932I194J51D01*
G01X197257D01*
G03X200972Y477204I-3437J6272D01*
G03X186666I-7153J0D01*
G03X190381Y470932I7152J0D01*
G01X190382D01*
G02X190479Y470706I-97J-175D01*
G01X190383Y470331D01*
G02X190189Y470181I-194J50D01*
G01X162730D01*
G02X162588Y470240I0J200D01*
G01X157559Y475269D01*
G02X157500Y475411I141J142D01*
G01Y571202D01*
G02X157559Y571344I200J0D01*
G01X160898Y574683D01*
G03X160904Y574689I-1411J1417D01*
G01X160925Y574710D01*
X160998Y574740D01*
X873056D01*
G02X873198Y574681I0J-200D01*
G01X876904Y570975D01*
G02X876963Y570833I-141J-142D01*
G01Y568041D01*
G02X876779Y567841I-200J-1D01*
G03Y549399I731J-9221D01*
G02X876963Y549199I-16J-199D01*
G01Y473412D01*
G02X876904Y473270I-200J0D01*
G37*
G36*
G01X1283465Y654614D02*
G02X1289339Y648740I0J-5874D01*
G01Y594488D01*
G02X1283465Y588614I-5874J0D01*
G01X607874D01*
G02X602000Y594488I0J5874D01*
G01Y648740D01*
G02X607874Y654614I5874J0D01*
G01X1283465D01*
G37*
G36*
G01X1060230Y368000D02*
X1083089D01*
G02X1083231Y367941I0J-200D01*
G01X1084329Y366843D01*
G02X1084388Y366701I-141J-142D01*
G01Y358891D01*
G02X1084313Y358735I-200J0D01*
G03Y353265I2187J-2735D01*
G02X1084388Y353109I-125J-156D01*
G01Y264661D01*
G02X1084329Y264519I-200J0D01*
G01X1083769Y263959D01*
G02X1083627Y263900I-142J141D01*
G01X1061511D01*
G02X1061369Y263959I0J200D01*
G01X1059859Y265469D01*
G02X1059800Y265611I141J142D01*
G01Y276389D01*
G02X1059859Y276531I200J0D01*
G01X1061869Y278541D01*
G02X1062011Y278600I142J-141D01*
G01X1074600D01*
G03X1076014Y279186I0J1999D01*
G01X1078914Y282086D01*
G03X1079500Y283500I-1413J1414D01*
G01Y309000D01*
G03X1078914Y310414I-1999J0D01*
G01X1076214Y313114D01*
G03X1074800Y313700I-1414J-1413D01*
G01X1061711D01*
G02X1061569Y313759I0J200D01*
G01X1059859Y315469D01*
G02X1059800Y315611I141J142D01*
G01Y330889D01*
G02X1059859Y331031I200J0D01*
G01X1061269Y332441D01*
G02X1061411Y332500I142J-141D01*
G01X1074500D01*
G03X1075914Y333086I0J1999D01*
G01X1078914Y336086D01*
G03X1079500Y337500I-1413J1414D01*
G01Y354500D01*
G03X1078914Y355914I-1999J0D01*
G01X1076914Y357914D01*
G03X1075500Y358500I-1414J-1413D01*
G01X1061911D01*
G02X1061769Y358559I0J200D01*
G01X1059859Y360469D01*
G02X1059800Y360611I141J142D01*
G01Y367570D01*
G02X1059859Y367712I200J0D01*
G01X1060088Y367941D01*
G02X1060230Y368000I142J-141D01*
G37*
G36*
G01X1061876Y521465D02*
X1088986D01*
G02X1089128Y521406I0J-200D01*
G01X1093216Y517318D01*
G02X1093275Y517176I-141J-142D01*
G01Y420395D01*
G02X1093162Y420215I-200J0D01*
G01X1092785Y420033D01*
X1092671Y420046D01*
X1092626Y420082D01*
G03X1090443Y420846I-2184J-2739D01*
G03X1086940Y417343I0J-3503D01*
G03X1086955Y417028I3503J9D01*
G01X1086958Y416986D01*
X1086932Y416906D01*
X1086704Y416657D01*
G02X1086556Y416592I-148J135D01*
G01X1060462D01*
G02X1060320Y416651I0J200D01*
G01X1059859Y417112D01*
X1059830Y417140D01*
X1059800Y417214D01*
Y422389D01*
G02X1059859Y422531I200J0D01*
G01X1061369Y424041D01*
G02X1061511Y424100I142J-141D01*
G01X1073600D01*
G03X1075014Y424686I0J1999D01*
G01X1078914Y428586D01*
G03X1079500Y430000I-1413J1414D01*
G01Y451000D01*
G03X1078914Y452414I-1999J0D01*
G01X1075714Y455614D01*
G03X1074300Y456200I-1414J-1413D01*
G01X1061211D01*
G02X1061069Y456259I0J200D01*
G01X1059859Y457469D01*
X1059830Y457497D01*
X1059800Y457571D01*
Y471389D01*
G02X1059859Y471531I200J0D01*
G01X1060869Y472541D01*
G02X1061011Y472600I142J-141D01*
G01X1074600D01*
G03X1076014Y473186I0J1999D01*
G01X1078914Y476086D01*
G03X1079500Y477500I-1413J1414D01*
G01Y498500D01*
G03X1078914Y499914I-1999J0D01*
G01X1076314Y502514D01*
G03X1074900Y503100I-1414J-1413D01*
G01X1061611D01*
G02X1061469Y503159I0J200D01*
G01X1059859Y504769D01*
X1059830Y504797D01*
X1059800Y504871D01*
Y519389D01*
G02X1059859Y519531I200J0D01*
G01X1061734Y521406D01*
G02X1061876Y521465I142J-141D01*
G37*
G36*
G01X1072665Y412592D02*
X1091089D01*
G02X1091231Y412533I0J-200D01*
G01X1093216Y410548D01*
G02X1093218Y410546I-140J-142D01*
G02X1093275Y410406I-143J-140D01*
G01Y379597D01*
G02X1093163Y379417I-200J0D01*
G01X1092790Y379233D01*
X1092677Y379244D01*
X1092632Y379279D01*
G03X1090500Y380002I-2131J-2779D01*
G03Y372998I0J-3502D01*
G03X1092632Y373721I1J3502D01*
G01X1092677Y373756D01*
X1092790Y373767D01*
X1093163Y373583D01*
G02X1093275Y373403I-88J-180D01*
G01Y229402D01*
G03X1093861Y227988I1999J0D01*
G01X1108931Y212918D01*
G03X1110345Y212332I1414J1413D01*
G01X1150123D01*
G02X1150265Y212273I0J-200D01*
G01X1163641Y198897D01*
G02X1163643Y198895I-140J-142D01*
G02X1163700Y198755I-143J-140D01*
G01Y187911D01*
G02X1163641Y187769I-200J0D01*
G01X1161681Y185809D01*
G02X1161539Y185750I-142J141D01*
G01X1146362D01*
G02X1146278Y185769I1J200D01*
G01X1146185Y185812D01*
X1146152Y185837D01*
X1146138Y185853D01*
G03X1143490Y187062I-2648J-2295D01*
G01X1143486D01*
G03X1142017Y186738I2J-3502D01*
G01X1141997Y186729D01*
X1141956Y186720D01*
G02X1141872I-42J195D01*
G01X1141829Y186729D01*
X1141809Y186738D01*
G03X1141480Y186870I-1467J-3180D01*
G03X1140336Y187062I-1144J-3310D01*
G01X1140335D01*
G03X1137730Y185901I0J-3503D01*
G03X1137689Y185854I2620J-2327D01*
G01X1137674Y185837D01*
X1137641Y185812D01*
X1137547Y185768D01*
G02X1137463Y185750I-83J182D01*
G01X1127309D01*
G02X1127153Y185825I0J200D01*
G01X1126962Y186061D01*
G02X1126918Y186187I156J125D01*
G01Y186237D01*
X1126923Y186258D01*
G03X1127002Y186999I-3423J740D01*
G01Y187000D01*
G03X1123500Y190502I-3502J0D01*
G01X1123493D01*
G03X1122681Y190406I2J-3502D01*
G01X1122671Y190404D01*
X1122647Y190400D01*
G02X1122523Y190424I-26J198D01*
G01X1122420Y190481D01*
X1122396Y190510D01*
X1122328Y190591D01*
X1122316Y190627D01*
G03X1119000Y193002I-3316J-1127D01*
G01X1118998D01*
G03X1116418Y191867I1J-3502D01*
G01X1116417Y191866D01*
X1116388Y191835D01*
X1116302Y191797D01*
G02X1116176Y191785I-81J183D01*
G01X1116146Y191792D01*
X1116123Y191804D01*
G03X1114503Y192202I-1622J-3104D01*
G01X1114500D01*
G03X1110998Y188700I0J-3502D01*
G01Y188699D01*
G03X1111849Y186411I3502J0D01*
G01X1111887Y186366D01*
X1111904Y186251D01*
X1111728Y185867D01*
X1111703Y185813D01*
X1111606Y185750D01*
X1105161D01*
G02X1105019Y185809I0J200D01*
G01X1090934Y199894D01*
G02X1090882Y200087I141J142D01*
G01Y200088D01*
G03X1091002Y200997I-3382J909D01*
G01Y201000D01*
G03X1088529Y204348I-3503J0D01*
G01X1088465Y204368D01*
X1088388Y204472D01*
Y352894D01*
G02X1088410Y352985I200J0D01*
G01X1088455Y353072D01*
G02X1088520Y353139I172J-102D01*
G03X1088530Y353145I-98J175D01*
G03X1088512Y358867I-2030J2855D01*
G01X1088492Y358881D01*
X1088460Y358918D01*
X1088411Y359013D01*
X1088400Y359035D01*
X1088388Y359082D01*
Y367612D01*
G03X1087802Y369026I-1999J0D01*
G01X1085414Y371414D01*
G03X1084000Y372000I-1414J-1413D01*
G01X1077861D01*
G02X1077719Y372059I0J200D01*
G01X1077059Y372719D01*
G02X1077000Y372861I141J142D01*
G01Y381589D01*
G02X1077057Y381729I200J0D01*
G01X1077058Y381730D01*
X1078914Y383586D01*
G03X1079500Y385000I-1413J1414D01*
G01Y401500D01*
G03X1078914Y402914I-1999J0D01*
G01X1076914Y404914D01*
G03X1075500Y405500I-1414J-1413D01*
G01X1073111D01*
G02X1072969Y405559I0J200D01*
G01X1072359Y406169D01*
G02X1072300Y406311I141J142D01*
G01Y412227D01*
G02X1072357Y412367I200J0D01*
G01X1072358Y412368D01*
X1072523Y412533D01*
G02X1072525Y412535I142J-140D01*
G02X1072665Y412592I140J-143D01*
G37*
G36*
G01X1102061Y377400D02*
X1173385D01*
G02X1173527Y377341I0J-200D01*
G01X1178112Y372756D01*
G02X1178171Y372614I-141J-142D01*
G01Y338657D01*
G02X1178140Y338551I-200J1D01*
G03X1177909Y337750I1271J-800D01*
G03X1178140Y336949I1502J-1D01*
G02X1178171Y336843I-169J-107D01*
G01Y335157D01*
G02X1178140Y335051I-200J1D01*
G03X1177909Y334250I1271J-800D01*
G03X1178140Y333449I1502J-1D01*
G02X1178171Y333343I-169J-107D01*
G01Y331657D01*
G02X1178140Y331551I-200J1D01*
G03X1177909Y330750I1271J-800D01*
G03X1178140Y329949I1502J-1D01*
G02X1178171Y329843I-169J-107D01*
G01Y328157D01*
G02X1178140Y328051I-200J1D01*
G03X1177909Y327250I1271J-800D01*
G03X1178140Y326449I1502J-1D01*
G02X1178171Y326343I-169J-107D01*
G01Y310199D01*
X1178168Y310183D01*
G03X1178149Y309942I1483J-238D01*
G03X1178168Y309701I1502J-3D01*
G01X1178171Y309685D01*
Y306199D01*
X1178168Y306183D01*
G03X1178149Y305942I1483J-238D01*
G03X1178168Y305701I1502J-3D01*
G01X1178171Y305685D01*
Y240892D01*
G02X1178112Y240750I-200J0D01*
G01X1174527Y237165D01*
G02X1174385Y237106I-142J141D01*
G01X1101890D01*
G02X1101748Y237165I0J200D01*
G01X1097334Y241579D01*
G02X1097275Y241721I141J142D01*
G01Y372614D01*
G02X1097334Y372756I200J0D01*
G01X1101919Y377341D01*
G02X1102061Y377400I142J-141D01*
G37*
G36*
G01X1101564Y521465D02*
X1174418D01*
G02X1174560Y521406I0J-200D01*
G01X1178112Y517854D01*
G02X1178171Y517712I-141J-142D01*
G01Y480974D01*
X1178161Y480931D01*
X1178151Y480910D01*
G03X1177998Y480250I1349J-660D01*
G03X1178151Y479590I1502J0D01*
G01X1178161Y479569D01*
X1178171Y479526D01*
Y477474D01*
X1178161Y477431D01*
X1178151Y477410D01*
G03X1177998Y476750I1349J-660D01*
G03X1178151Y476090I1502J0D01*
G01X1178161Y476069D01*
X1178171Y476026D01*
Y473974D01*
X1178161Y473931D01*
X1178151Y473910D01*
G03X1177998Y473250I1349J-660D01*
G03X1178151Y472590I1502J0D01*
G01X1178161Y472569D01*
X1178171Y472526D01*
Y470474D01*
X1178161Y470431D01*
X1178151Y470410D01*
G03X1177998Y469750I1349J-660D01*
G03X1178151Y469090I1502J0D01*
G01X1178161Y469069D01*
X1178171Y469026D01*
Y386186D01*
G02X1178112Y386044I-200J0D01*
G01X1173527Y381459D01*
G02X1173385Y381400I-142J141D01*
G01X1102061D01*
G02X1101919Y381459I0J200D01*
G01X1097334Y386044D01*
G02X1097275Y386186I141J142D01*
G01Y517176D01*
G02X1097334Y517318I200J0D01*
G01X1101422Y521406D01*
G02X1101564Y521465I142J-141D01*
G37*
G36*
G01X1205589Y291800D02*
X1183977D01*
G02X1183835Y291859I0J200D01*
G01X1182230Y293464D01*
G02X1182171Y293606I141J142D01*
G01Y348245D01*
G02X1182208Y348361I200J0D01*
G03Y350107I-1222J873D01*
G02X1182171Y350223I163J116D01*
G01Y474987D01*
G02X1182230Y475129I200J0D01*
G01X1186142Y479041D01*
G02X1186284Y479100I142J-141D01*
G01X1257489D01*
G02X1257631Y479041I0J-200D01*
G01X1261441Y475231D01*
G02X1261500Y475089I-141J-142D01*
G01Y303511D01*
G02X1261441Y303369I-200J0D01*
G01X1258631Y300559D01*
G02X1258489Y300500I-142J141D01*
G01X1215200D01*
G03X1213786Y299914I0J-1999D01*
G01X1205731Y291859D01*
G02X1205589Y291800I-142J141D01*
G37*
%LPD*%
G75*
G36*
G01X637793Y40521D02*
G02X634698Y44000I408J3479D01*
G02X634903Y45182I3502J1D01*
G03Y45318I-188J68D01*
G02X634698Y46500I3297J1181D01*
G02X638058Y50000I3503J0D01*
G03X638215Y50086I-7J200D01*
G02X641100Y51602I2885J-1987D01*
G02X644602Y48100I0J-3502D01*
G02X643351Y45417I-3503J0D01*
G01X643318Y45389D01*
X643281Y45313D01*
X643268Y44930D01*
X643299Y44852D01*
X643330Y44822D01*
G02X644402Y42300I-2431J-2522D01*
G02X640900Y38798I-3502J0D01*
G02X637939Y40429I0J3503D01*
G03X637793Y40521I-169J-107D01*
G37*
G36*
G01X1075308Y93847D02*
G02X1077200Y94402I1892J-2947D01*
G02Y87398I0J-3502D01*
G02X1075308Y87953I0J3502D01*
G03X1075092I-108J-168D01*
G02X1073200Y87398I-1892J2947D01*
G02Y94402I0J3502D01*
G02X1075092Y93847I0J-3502D01*
G03X1075308I108J168D01*
G37*
G36*
G01X68400Y93092D02*
X67972Y93157D01*
X67879Y93125D01*
X67844Y93087D01*
G02Y106361I-7214J6637D01*
G01X67879Y106323D01*
X67972Y106291D01*
X68400Y106356D01*
X68479Y106415D01*
X68500Y106461D01*
G02X82795Y115526I14295J-6739D01*
G02Y83922I0J-15802D01*
G02X68500Y92987I0J15804D01*
G01X68479Y93033D01*
X68400Y93092D01*
G37*
G36*
G01X1181839Y169249D02*
G02X1183021Y169454I1181J-3297D01*
G02X1184203Y169249I1J-3502D01*
G03X1184339I68J188D01*
G02X1185521Y169454I1181J-3297D01*
G02X1186928Y169160I2J-3502D01*
G03X1187094Y169162I81J183D01*
G02X1188600Y169502I1505J-3162D01*
G02X1192102Y166000I0J-3502D01*
G02X1191763Y164496I-3502J-1D01*
G03X1191764Y164322I181J-86D01*
G02X1192120Y162782I-3146J-1538D01*
G02X1188618Y159280I-3502J0D01*
G02X1186979Y159687I0J3502D01*
G03X1186812Y159696I-93J-177D01*
G02X1185521Y159450I-1289J3256D01*
G02X1184339Y159655I-1J3502D01*
G03X1184203I-68J-188D01*
G02X1183021Y159450I-1181J3297D01*
G02X1181839Y159655I-1J3502D01*
G03X1181703I-68J-188D01*
G02X1180521Y159450I-1181J3297D01*
G02X1179102Y159750I-1J3502D01*
G03X1178940I-81J-183D01*
G02X1177521Y159450I-1418J3202D01*
G02X1174018Y162952I-1J3502D01*
G02X1174319Y164371I3503J-2D01*
G03Y164533I-183J81D01*
G02X1174018Y165952I3202J1421D01*
G02X1177521Y169454I3503J-1D01*
G02X1178940Y169154I1J-3502D01*
G03X1179102I81J183D01*
G02X1180521Y169454I1418J-3202D01*
G02X1181703Y169249I1J-3502D01*
G03X1181839I68J188D01*
G37*
G36*
G01X1018570Y169974D02*
X1018623Y170080D01*
G03X1018636Y170225I-179J89D01*
G02X1018498Y171200I3364J973D01*
G02X1025502I3502J0D01*
G02X1023239Y167924I-3503J0D01*
G03X1023130Y167826I70J-187D01*
G01X1023077Y167720D01*
G03X1023064Y167575I179J-89D01*
G02X1023202Y166600I-3364J-973D01*
G02X1023053Y165589I-3502J0D01*
G01X1023042Y165551D01*
X1023049Y165475D01*
X1023211Y165158D01*
X1023269Y165108D01*
X1023306Y165095D01*
G02X1025670Y161783I-1138J-3312D01*
G02X1024458Y159133I-3503J0D01*
G01X1024424Y159104D01*
X1024389Y159026D01*
Y158634D01*
X1024424Y158556D01*
X1024458Y158527D01*
G02X1025670Y155877I-2291J-2650D01*
G02X1022168Y152374I-3502J-1D01*
G02X1021810Y152393I6J3503D01*
G01X1021764Y152398D01*
X1021678Y152366D01*
X1021395Y152070D01*
X1021367Y151983D01*
X1021374Y151936D01*
G02X1021412Y151424I-3465J-515D01*
G02X1014406I-3503J0D01*
G02X1014645Y152693I3503J-3D01*
G03X1014641Y152848I-187J73D01*
G02X1014334Y154280I3196J1434D01*
G02X1015483Y156874I3503J0D01*
G03X1015548Y157037I-134J148D01*
G02X1015538Y157310I3492J265D01*
G02X1015837Y158728I3502J2D01*
G03Y158891I-183J82D01*
G02X1015528Y160330I3193J1438D01*
G02X1017278Y163363I3503J0D01*
G01X1017320Y163387D01*
X1017372Y163467D01*
X1017417Y163885D01*
X1017383Y163973D01*
X1017347Y164006D01*
G02X1016198Y166600I2354J2594D01*
G02X1018461Y169876I3503J0D01*
G03X1018570Y169974I-70J187D01*
G37*
G36*
G01X1019816Y188686D02*
G02X1020116Y187267I-3202J-1418D01*
G02X1013112I-3502J0D01*
G02X1013412Y188686I3502J1D01*
G03Y188848I-183J81D01*
G02X1013112Y190267I3202J1418D01*
G02X1020116I3502J0D01*
G02X1019816Y188848I-3502J-1D01*
G03Y188686I183J-81D01*
G37*
G36*
G01X1168298Y209581D02*
G02X1167998Y211000I3202J1418D01*
G02X1168298Y212419I3502J1D01*
G03Y212581I-182J81D01*
G02X1167998Y214000I3202J1418D01*
G02X1171500Y217502I3502J0D01*
G02X1172919Y217202I1J-3502D01*
G03X1173081I81J182D01*
G02X1174500Y217502I1418J-3202D01*
G02X1178002Y214000I0J-3502D01*
G02X1177702Y212581I-3502J-1D01*
G03Y212419I182J-81D01*
G02X1178002Y211000I-3202J-1418D01*
G02X1177702Y209581I-3502J-1D01*
G03Y209419I182J-81D01*
G02X1178002Y208000I-3202J-1418D01*
G02X1177702Y206581I-3502J-1D01*
G03Y206419I182J-81D01*
G02X1178002Y205000I-3202J-1418D01*
G02X1174500Y201498I-3502J0D01*
G02X1173081Y201798I-1J3502D01*
G03X1172919I-81J-182D01*
G02X1171500Y201498I-1418J3202D01*
G02X1167998Y205000I0J3502D01*
G02X1168298Y206419I3502J1D01*
G03Y206581I-182J81D01*
G02X1167998Y208000I3202J1418D01*
G02X1168298Y209419I3502J1D01*
G03Y209581I-182J81D01*
G37*
G36*
G01X43781Y349915D02*
G02X48780Y354726I4999J-192D01*
G02X53782Y349724I0J-5002D01*
G02X48971Y344725I-5003J0D01*
G03X48779Y344533I8J-200D01*
G02X43780Y339722I-4999J192D01*
G02X38778Y344724I0J5002D01*
G02X43589Y349723I5003J0D01*
G03X43781Y349915I-8J200D01*
G37*
G36*
G01X805330Y274583D02*
G02X804996Y276075I3169J1493D01*
G02X812004I3504J0D01*
G02X811670Y274583I-3503J1D01*
G03Y274413I181J-85D01*
G02X812003Y272925I-3170J-1491D01*
G02X804997I-3503J0D01*
G02X805330Y274413I3503J-3D01*
G03Y274583I-181J85D01*
G37*
G36*
G01X301598Y162515D02*
X301906D01*
G03X302075Y162609I-1J200D01*
G02X306752Y165200I4677J-2926D01*
G02X312267Y159685I0J-5515D01*
G02X309676Y155008I-5517J0D01*
G03X309582Y154839I106J-170D01*
G01Y154531D01*
G03X309676Y154362I200J1D01*
G02Y145008I-2925J-4677D01*
G03X309582Y144839I106J-170D01*
G01Y144531D01*
G03X309676Y144362I200J1D01*
G02Y135008I-2925J-4677D01*
G03X309582Y134839I106J-170D01*
G01Y134531D01*
G03X309676Y134362I200J1D01*
G02X312267Y129685I-2926J-4677D01*
G02X306752Y124170I-5515J0D01*
G02X302075Y126761I0J5517D01*
G03X301906Y126855I-170J-106D01*
G01X301598D01*
G03X301429Y126761I1J-200D01*
G02X296752Y124170I-4677J2926D01*
G02X291237Y129685I0J5515D01*
G02X293828Y134362I5517J0D01*
G03X293922Y134531I-106J170D01*
G01Y134839D01*
G03X293828Y135008I-200J-1D01*
G02Y144362I2925J4677D01*
G03X293922Y144531I-106J170D01*
G01Y144839D01*
G03X293828Y145008I-200J-1D01*
G02Y154362I2925J4677D01*
G03X293922Y154531I-106J170D01*
G01Y154839D01*
G03X293828Y155008I-200J-1D01*
G02X291237Y159685I2926J4677D01*
G02X296752Y165200I5515J0D01*
G02X301429Y162609I0J-5517D01*
G03X301598Y162515I170J106D01*
G37*
G36*
G01X336598D02*
X336906D01*
G03X337075Y162609I-1J200D01*
G02X341752Y165200I4677J-2926D01*
G02X347267Y159685I0J-5515D01*
G02X344676Y155008I-5517J0D01*
G03X344582Y154839I106J-170D01*
G01Y154531D01*
G03X344676Y154362I200J1D01*
G02Y145008I-2925J-4677D01*
G03X344582Y144839I106J-170D01*
G01Y144531D01*
G03X344676Y144362I200J1D01*
G02Y135008I-2925J-4677D01*
G03X344582Y134839I106J-170D01*
G01Y134531D01*
G03X344676Y134362I200J1D01*
G02X347267Y129685I-2926J-4677D01*
G02X341752Y124170I-5515J0D01*
G02X337075Y126761I0J5517D01*
G03X336906Y126855I-170J-106D01*
G01X336598D01*
G03X336429Y126761I1J-200D01*
G02X331752Y124170I-4677J2926D01*
G02X326237Y129685I0J5515D01*
G02X328828Y134362I5517J0D01*
G03X328922Y134531I-106J170D01*
G01Y134839D01*
G03X328828Y135008I-200J-1D01*
G02Y144362I2925J4677D01*
G03X328922Y144531I-106J170D01*
G01Y144839D01*
G03X328828Y145008I-200J-1D01*
G02Y154362I2925J4677D01*
G03X328922Y154531I-106J170D01*
G01Y154839D01*
G03X328828Y155008I-200J-1D01*
G02X326237Y159685I2926J4677D01*
G02X331752Y165200I5515J0D01*
G02X336429Y162609I0J-5517D01*
G03X336598Y162515I170J106D01*
G37*
G36*
G01X371598D02*
X371906D01*
G03X372075Y162609I-1J200D01*
G02X376752Y165200I4677J-2926D01*
G02X382267Y159685I0J-5515D01*
G02X379676Y155008I-5517J0D01*
G03X379582Y154839I106J-170D01*
G01Y154531D01*
G03X379676Y154362I200J1D01*
G02Y145008I-2925J-4677D01*
G03X379582Y144839I106J-170D01*
G01Y144531D01*
G03X379676Y144362I200J1D01*
G02Y135008I-2925J-4677D01*
G03X379582Y134839I106J-170D01*
G01Y134531D01*
G03X379676Y134362I200J1D01*
G02X382267Y129685I-2926J-4677D01*
G02X376752Y124170I-5515J0D01*
G02X372075Y126761I0J5517D01*
G03X371906Y126855I-170J-106D01*
G01X371598D01*
G03X371429Y126761I1J-200D01*
G02X366752Y124170I-4677J2926D01*
G02X361237Y129685I0J5515D01*
G02X363828Y134362I5517J0D01*
G03X363922Y134531I-106J170D01*
G01Y134839D01*
G03X363828Y135008I-200J-1D01*
G02Y144362I2925J4677D01*
G03X363922Y144531I-106J170D01*
G01Y144839D01*
G03X363828Y145008I-200J-1D01*
G02Y154362I2925J4677D01*
G03X363922Y154531I-106J170D01*
G01Y154839D01*
G03X363828Y155008I-200J-1D01*
G02X361237Y159685I2926J4677D01*
G02X366752Y165200I5515J0D01*
G02X371429Y162609I0J-5517D01*
G03X371598Y162515I170J106D01*
G37*
G36*
G01X169210Y222261D02*
Y222263D01*
G02X172712Y225765I3502J0D01*
G02X176210Y222440I0J-3503D01*
G03X176386Y222251I200J9D01*
G02X179476Y218775I-410J-3476D01*
G02X175976Y215275I-3500J0D01*
G02X174191Y215764I-1J3500D01*
G03X174027Y215782I-102J-172D01*
G02X172936Y215608I-1090J3328D01*
G01X172934D01*
G02X169432Y219110I0J3502D01*
G01Y219113D01*
G02X169669Y220379I3502J0D01*
G03X169657Y220549I-186J72D01*
G02X169210Y222261I3055J1712D01*
G37*
G36*
G01X600998Y203000D02*
Y203003D01*
G02X601203Y204183I3502J-1D01*
G03Y204317I-188J67D01*
G02X600998Y205497I3297J1181D01*
G01Y205500D01*
G02X608002I3502J0D01*
G01Y205497D01*
G02X607797Y204317I-3502J1D01*
G03Y204183I188J-67D01*
G02X608002Y203003I-3297J-1181D01*
G01Y203000D01*
G02X607133Y200690I-3503J-1D01*
G03X607083Y200559I150J-132D01*
G01Y200441D01*
G03X607133Y200310I200J1D01*
G02X608002Y198000I-2634J-2309D01*
G01Y197997D01*
G02X607797Y196817I-3502J1D01*
G03Y196683I188J-67D01*
G02X608002Y195503I-3297J-1181D01*
G01Y195500D01*
G02X600998I-3502J0D01*
G01Y195503D01*
G02X601203Y196683I3502J-1D01*
G03Y196817I-188J67D01*
G02X600998Y197997I3297J1181D01*
G01Y198000D01*
G02X601867Y200310I3503J1D01*
G03X601917Y200441I-150J132D01*
G01Y200559D01*
G03X601867Y200690I-200J-1D01*
G02X600998Y203000I2634J2309D01*
G37*
G36*
G01X622498D02*
Y203003D01*
G02X622703Y204183I3502J-1D01*
G03Y204317I-188J67D01*
G02X622498Y205497I3297J1181D01*
G01Y205500D01*
G02X629502I3502J0D01*
G01Y205497D01*
G02X629297Y204317I-3502J1D01*
G03Y204183I188J-67D01*
G02X629502Y203003I-3297J-1181D01*
G01Y203000D01*
G02X628633Y200690I-3503J-1D01*
G03X628583Y200559I150J-132D01*
G01Y200441D01*
G03X628633Y200310I200J1D01*
G02X629502Y198000I-2634J-2309D01*
G01Y197997D01*
G02X629297Y196817I-3502J1D01*
G03Y196683I188J-67D01*
G02X629502Y195503I-3297J-1181D01*
G01Y195500D01*
G02X622498I-3502J0D01*
G01Y195503D01*
G02X622703Y196683I3502J-1D01*
G03Y196817I-188J67D01*
G02X622498Y197997I3297J1181D01*
G01Y198000D01*
G02X623367Y200310I3503J1D01*
G03X623417Y200441I-150J132D01*
G01Y200559D01*
G03X623367Y200690I-200J-1D01*
G02X622498Y203000I2634J2309D01*
G37*
G36*
G01X643998D02*
Y203003D01*
G02X644203Y204183I3502J-1D01*
G03Y204317I-188J67D01*
G02X643998Y205497I3297J1181D01*
G01Y205500D01*
G02X651002I3502J0D01*
G01Y205497D01*
G02X650797Y204317I-3502J1D01*
G03Y204183I188J-67D01*
G02X651002Y203003I-3297J-1181D01*
G01Y203000D01*
G02X650133Y200690I-3503J-1D01*
G03X650083Y200559I150J-132D01*
G01Y200441D01*
G03X650133Y200310I200J1D01*
G02X651002Y198000I-2634J-2309D01*
G01Y197997D01*
G02X650797Y196817I-3502J1D01*
G03Y196683I188J-67D01*
G02X651002Y195503I-3297J-1181D01*
G01Y195500D01*
G02X643998I-3502J0D01*
G01Y195503D01*
G02X644203Y196683I3502J-1D01*
G03Y196817I-188J67D01*
G02X643998Y197997I3297J1181D01*
G01Y198000D01*
G02X644867Y200310I3503J1D01*
G03X644917Y200441I-150J132D01*
G01Y200559D01*
G03X644867Y200690I-200J-1D01*
G02X643998Y203000I2634J2309D01*
G37*
G36*
G01X665498D02*
Y203003D01*
G02X665703Y204183I3502J-1D01*
G03Y204317I-188J67D01*
G02X665498Y205497I3297J1181D01*
G01Y205500D01*
G02X672502I3502J0D01*
G01Y205497D01*
G02X672297Y204317I-3502J1D01*
G03Y204183I188J-67D01*
G02X672502Y203003I-3297J-1181D01*
G01Y203000D01*
G02X671633Y200690I-3503J-1D01*
G03X671583Y200559I150J-132D01*
G01Y200441D01*
G03X671633Y200310I200J1D01*
G02X672502Y198000I-2634J-2309D01*
G01Y197997D01*
G02X672297Y196817I-3502J1D01*
G03Y196683I188J-67D01*
G02X672502Y195503I-3297J-1181D01*
G01Y195500D01*
G02X665498I-3502J0D01*
G01Y195503D01*
G02X665703Y196683I3502J-1D01*
G03Y196817I-188J67D01*
G02X665498Y197997I3297J1181D01*
G01Y198000D01*
G02X666367Y200310I3503J1D01*
G03X666417Y200441I-150J132D01*
G01Y200559D01*
G03X666367Y200690I-200J-1D01*
G02X665498Y203000I2634J2309D01*
G37*
G36*
G01X686998D02*
Y203003D01*
G02X687203Y204183I3502J-1D01*
G03Y204317I-188J67D01*
G02X686998Y205497I3297J1181D01*
G01Y205500D01*
G02X694002I3502J0D01*
G01Y205497D01*
G02X693797Y204317I-3502J1D01*
G03Y204183I188J-67D01*
G02X694002Y203003I-3297J-1181D01*
G01Y203000D01*
G02X693133Y200690I-3503J-1D01*
G03X693083Y200559I150J-132D01*
G01Y200441D01*
G03X693133Y200310I200J1D01*
G02X694002Y198000I-2634J-2309D01*
G01Y197997D01*
G02X693797Y196817I-3502J1D01*
G03Y196683I188J-67D01*
G02X694002Y195503I-3297J-1181D01*
G01Y195500D01*
G02X686998I-3502J0D01*
G01Y195503D01*
G02X687203Y196683I3502J-1D01*
G03Y196817I-188J67D01*
G02X686998Y197997I3297J1181D01*
G01Y198000D01*
G02X687867Y200310I3503J1D01*
G03X687917Y200441I-150J132D01*
G01Y200559D01*
G03X687867Y200690I-200J-1D01*
G02X686998Y203000I2634J2309D01*
G37*
G36*
G01X708488D02*
Y203003D01*
G02X708693Y204183I3502J-1D01*
G03Y204317I-188J67D01*
G02X708488Y205497I3297J1181D01*
G01Y205500D01*
G02X715492I3502J0D01*
G01Y205497D01*
G02X715287Y204317I-3502J1D01*
G03Y204183I188J-67D01*
G02X715492Y203003I-3297J-1181D01*
G01Y203000D01*
G02X714623Y200690I-3503J-1D01*
G03X714573Y200559I150J-132D01*
G01Y200441D01*
G03X714623Y200310I200J1D01*
G02X715492Y198000I-2634J-2309D01*
G01Y197997D01*
G02X715287Y196817I-3502J1D01*
G03Y196683I188J-67D01*
G02X715492Y195503I-3297J-1181D01*
G01Y195500D01*
G02X708488I-3502J0D01*
G01Y195503D01*
G02X708693Y196683I3502J-1D01*
G03Y196817I-188J67D01*
G02X708488Y197997I3297J1181D01*
G01Y198000D01*
G02X709357Y200310I3503J1D01*
G03X709407Y200441I-150J132D01*
G01Y200559D01*
G03X709357Y200690I-200J-1D01*
G02X708488Y203000I2634J2309D01*
G37*
G36*
G01X729988D02*
Y203003D01*
G02X730193Y204183I3502J-1D01*
G03Y204317I-188J67D01*
G02X729988Y205497I3297J1181D01*
G01Y205500D01*
G02X736992I3502J0D01*
G01Y205497D01*
G02X736787Y204317I-3502J1D01*
G03Y204183I188J-67D01*
G02X736992Y203003I-3297J-1181D01*
G01Y203000D01*
G02X736123Y200690I-3503J-1D01*
G03X736073Y200559I150J-132D01*
G01Y200441D01*
G03X736123Y200310I200J1D01*
G02X736992Y198000I-2634J-2309D01*
G01Y197997D01*
G02X736787Y196817I-3502J1D01*
G03Y196683I188J-67D01*
G02X736992Y195503I-3297J-1181D01*
G01Y195500D01*
G02X729988I-3502J0D01*
G01Y195503D01*
G02X730193Y196683I3502J-1D01*
G03Y196817I-188J67D01*
G02X729988Y197997I3297J1181D01*
G01Y198000D01*
G02X730857Y200310I3503J1D01*
G03X730907Y200441I-150J132D01*
G01Y200559D01*
G03X730857Y200690I-200J-1D01*
G02X729988Y203000I2634J2309D01*
G37*
G36*
G01X293498Y203500D02*
Y203503D01*
G02X293703Y204683I3502J-1D01*
G03Y204817I-188J67D01*
G02X293498Y205997I3297J1181D01*
G01Y206000D01*
G02X300502I3502J0D01*
G01Y205997D01*
G02X300297Y204817I-3502J1D01*
G03Y204683I188J-67D01*
G02X300502Y203503I-3297J-1181D01*
G01Y203500D01*
G02X299633Y201190I-3503J-1D01*
G03X299583Y201059I150J-132D01*
G01Y200941D01*
G03X299633Y200810I200J1D01*
G02X300502Y198500I-2634J-2309D01*
G01Y198497D01*
G02X300297Y197317I-3502J1D01*
G03Y197183I188J-67D01*
G02X300502Y196003I-3297J-1181D01*
G01Y196000D01*
G02X293498I-3502J0D01*
G01Y196003D01*
G02X293703Y197183I3502J-1D01*
G03Y197317I-188J67D01*
G02X293498Y198497I3297J1181D01*
G01Y198500D01*
G02X294367Y200810I3503J1D01*
G03X294417Y200941I-150J132D01*
G01Y201059D01*
G03X294367Y201190I-200J-1D01*
G02X293498Y203500I2634J2309D01*
G37*
G36*
G01X314998D02*
Y203503D01*
G02X315203Y204683I3502J-1D01*
G03Y204817I-188J67D01*
G02X314998Y205997I3297J1181D01*
G01Y206000D01*
G02X322002I3502J0D01*
G01Y205997D01*
G02X321797Y204817I-3502J1D01*
G03Y204683I188J-67D01*
G02X322002Y203503I-3297J-1181D01*
G01Y203500D01*
G02X321133Y201190I-3503J-1D01*
G03X321083Y201059I150J-132D01*
G01Y200941D01*
G03X321133Y200810I200J1D01*
G02X322002Y198500I-2634J-2309D01*
G01Y198497D01*
G02X321797Y197317I-3502J1D01*
G03Y197183I188J-67D01*
G02X322002Y196003I-3297J-1181D01*
G01Y196000D01*
G02X314998I-3502J0D01*
G01Y196003D01*
G02X315203Y197183I3502J-1D01*
G03Y197317I-188J67D01*
G02X314998Y198497I3297J1181D01*
G01Y198500D01*
G02X315867Y200810I3503J1D01*
G03X315917Y200941I-150J132D01*
G01Y201059D01*
G03X315867Y201190I-200J-1D01*
G02X314998Y203500I2634J2309D01*
G37*
G36*
G01X336498D02*
Y203503D01*
G02X336703Y204683I3502J-1D01*
G03Y204817I-188J67D01*
G02X336498Y205997I3297J1181D01*
G01Y206000D01*
G02X343502I3502J0D01*
G01Y205997D01*
G02X343297Y204817I-3502J1D01*
G03Y204683I188J-67D01*
G02X343502Y203503I-3297J-1181D01*
G01Y203500D01*
G02X342633Y201190I-3503J-1D01*
G03X342583Y201059I150J-132D01*
G01Y200941D01*
G03X342633Y200810I200J1D01*
G02X343502Y198500I-2634J-2309D01*
G01Y198497D01*
G02X343297Y197317I-3502J1D01*
G03Y197183I188J-67D01*
G02X343502Y196003I-3297J-1181D01*
G01Y196000D01*
G02X336498I-3502J0D01*
G01Y196003D01*
G02X336703Y197183I3502J-1D01*
G03Y197317I-188J67D01*
G02X336498Y198497I3297J1181D01*
G01Y198500D01*
G02X337367Y200810I3503J1D01*
G03X337417Y200941I-150J132D01*
G01Y201059D01*
G03X337367Y201190I-200J-1D01*
G02X336498Y203500I2634J2309D01*
G37*
G36*
G01X357998D02*
Y203503D01*
G02X358203Y204683I3502J-1D01*
G03Y204817I-188J67D01*
G02X357998Y205997I3297J1181D01*
G01Y206000D01*
G02X365002I3502J0D01*
G01Y205997D01*
G02X364797Y204817I-3502J1D01*
G03Y204683I188J-67D01*
G02X365002Y203503I-3297J-1181D01*
G01Y203500D01*
G02X364133Y201190I-3503J-1D01*
G03X364083Y201059I150J-132D01*
G01Y200941D01*
G03X364133Y200810I200J1D01*
G02X365002Y198500I-2634J-2309D01*
G01Y198497D01*
G02X364797Y197317I-3502J1D01*
G03Y197183I188J-67D01*
G02X365002Y196003I-3297J-1181D01*
G01Y196000D01*
G02X357998I-3502J0D01*
G01Y196003D01*
G02X358203Y197183I3502J-1D01*
G03Y197317I-188J67D01*
G02X357998Y198497I3297J1181D01*
G01Y198500D01*
G02X358867Y200810I3503J1D01*
G03X358917Y200941I-150J132D01*
G01Y201059D01*
G03X358867Y201190I-200J-1D01*
G02X357998Y203500I2634J2309D01*
G37*
G36*
G01X379498D02*
Y203503D01*
G02X379703Y204683I3502J-1D01*
G03Y204817I-188J67D01*
G02X379498Y205997I3297J1181D01*
G01Y206000D01*
G02X386502I3502J0D01*
G01Y205997D01*
G02X386297Y204817I-3502J1D01*
G03Y204683I188J-67D01*
G02X386502Y203503I-3297J-1181D01*
G01Y203500D01*
G02X385633Y201190I-3503J-1D01*
G03X385583Y201059I150J-132D01*
G01Y200941D01*
G03X385633Y200810I200J1D01*
G02X386502Y198500I-2634J-2309D01*
G01Y198497D01*
G02X386297Y197317I-3502J1D01*
G03Y197183I188J-67D01*
G02X386502Y196003I-3297J-1181D01*
G01Y196000D01*
G02X379498I-3502J0D01*
G01Y196003D01*
G02X379703Y197183I3502J-1D01*
G03Y197317I-188J67D01*
G02X379498Y198497I3297J1181D01*
G01Y198500D01*
G02X380367Y200810I3503J1D01*
G03X380417Y200941I-150J132D01*
G01Y201059D01*
G03X380367Y201190I-200J-1D01*
G02X379498Y203500I2634J2309D01*
G37*
G36*
G01X400998D02*
Y203503D01*
G02X401203Y204683I3502J-1D01*
G03Y204817I-188J67D01*
G02X400998Y205997I3297J1181D01*
G01Y206000D01*
G02X408002I3502J0D01*
G01Y205997D01*
G02X407797Y204817I-3502J1D01*
G03Y204683I188J-67D01*
G02X408002Y203503I-3297J-1181D01*
G01Y203500D01*
G02X407133Y201190I-3503J-1D01*
G03X407083Y201059I150J-132D01*
G01Y200941D01*
G03X407133Y200810I200J1D01*
G02X408002Y198500I-2634J-2309D01*
G01Y198497D01*
G02X407797Y197317I-3502J1D01*
G03Y197183I188J-67D01*
G02X408002Y196003I-3297J-1181D01*
G01Y196000D01*
G02X400998I-3502J0D01*
G01Y196003D01*
G02X401203Y197183I3502J-1D01*
G03Y197317I-188J67D01*
G02X400998Y198497I3297J1181D01*
G01Y198500D01*
G02X401867Y200810I3503J1D01*
G03X401917Y200941I-150J132D01*
G01Y201059D01*
G03X401867Y201190I-200J-1D01*
G02X400998Y203500I2634J2309D01*
G37*
G36*
G01X422498D02*
Y203503D01*
G02X422703Y204683I3502J-1D01*
G03Y204817I-188J67D01*
G02X422498Y205997I3297J1181D01*
G01Y206000D01*
G02X429502I3502J0D01*
G01Y205997D01*
G02X429297Y204817I-3502J1D01*
G03Y204683I188J-67D01*
G02X429502Y203503I-3297J-1181D01*
G01Y203500D01*
G02X428633Y201190I-3503J-1D01*
G03X428583Y201059I150J-132D01*
G01Y200941D01*
G03X428633Y200810I200J1D01*
G02X429502Y198500I-2634J-2309D01*
G01Y198497D01*
G02X429297Y197317I-3502J1D01*
G03Y197183I188J-67D01*
G02X429502Y196003I-3297J-1181D01*
G01Y196000D01*
G02X422498I-3502J0D01*
G01Y196003D01*
G02X422703Y197183I3502J-1D01*
G03Y197317I-188J67D01*
G02X422498Y198497I3297J1181D01*
G01Y198500D01*
G02X423367Y200810I3503J1D01*
G03X423417Y200941I-150J132D01*
G01Y201059D01*
G03X423367Y201190I-200J-1D01*
G02X422498Y203500I2634J2309D01*
G37*
G36*
G01X148832Y226563D02*
G02X149247Y228219I3502J2D01*
G03Y228407I-176J94D01*
G02X148832Y230061I3087J1654D01*
G01Y230063D01*
G02X152065Y233555I3502J0D01*
G03X152211Y233636I-15J200D01*
G02X155034Y235066I2823J-2071D01*
G02X158536Y231563I-1J-3503D01*
G01Y231561D01*
G02X158121Y229907I-3502J0D01*
G03Y229719I176J-94D01*
G02X158536Y228063I-3087J-1654D01*
G02X158121Y226407I-3502J-2D01*
G03Y226219I176J-94D01*
G02X158536Y224565I-3087J-1654D01*
G01Y224563D01*
G02X155303Y221071I-3502J0D01*
G03X155157Y220990I15J-200D01*
G02X154140Y220062I-2823J2073D01*
G03X154048Y219846I103J-171D01*
G02X154136Y219063I-3414J-780D01*
G02X153716Y217398I-3502J-2D01*
G01X153692Y217355D01*
X153691Y217258D01*
X153880Y216877D01*
X153959Y216820D01*
X154007Y216813D01*
G02X156982Y213350I-528J-3463D01*
G02X149978I-3502J0D01*
G01Y213354D01*
G02X150398Y215015I3502J-2D01*
G01X150422Y215058D01*
X150423Y215155D01*
X150234Y215536D01*
X150155Y215593D01*
X150107Y215600D01*
G02X147132Y219063I528J3463D01*
G02X148828Y222064I3503J0D01*
G03X148920Y222280I-103J171D01*
G02X148832Y223063I3414J780D01*
G02X149247Y224719I3502J2D01*
G03Y224907I-176J94D01*
G02X148832Y226563I3087J1654D01*
G37*
G36*
G01X195760Y248602D02*
G02X197179Y248302I1J-3502D01*
G03X197341I81J183D01*
G02X198760Y248602I1418J-3202D01*
G02X200179Y248302I1J-3502D01*
G03X200341I81J183D01*
G02X201758Y248602I1418J-3202D01*
G01X201760D01*
G02X205262Y245100I0J-3502D01*
G01Y245098D01*
G02X204962Y243681I-3502J1D01*
G03Y243519I183J-81D01*
G02X205262Y242102I-3202J-1418D01*
G01Y242100D01*
G02X201760Y238598I-3502J0D01*
G01X201758D01*
G02X200341Y238898I1J3502D01*
G03X200179I-81J-183D01*
G02X198760Y238598I-1418J3202D01*
G02X197341Y238898I-1J3502D01*
G03X197179I-81J-183D01*
G02X195760Y238598I-1418J3202D01*
G02X194341Y238898I-1J3502D01*
G03X194179I-81J-183D01*
G02X192760Y238598I-1418J3202D01*
G02X191341Y238898I-1J3502D01*
G03X191179I-81J-183D01*
G02X189762Y238598I-1418J3202D01*
G01X189760D01*
G02X186258Y242100I0J3502D01*
G01Y242102D01*
G02X186558Y243519I3502J-1D01*
G03Y243681I-183J81D01*
G02X186258Y245098I3202J1418D01*
G01Y245100D01*
G02X189760Y248602I3502J0D01*
G01X189762D01*
G02X191179Y248302I-1J-3502D01*
G03X191341I81J183D01*
G02X192760Y248602I1418J-3202D01*
G02X194179Y248302I1J-3502D01*
G03X194341I81J183D01*
G02X195760Y248602I1418J-3202D01*
G37*
G36*
G01X394998Y242500D02*
Y242501D01*
G02X395719Y244628I3502J-1D01*
G03Y244872I-159J122D01*
G02X394998Y246999I2781J2128D01*
G01Y247000D01*
G02X402002I3502J0D01*
G01Y246999D01*
G02X401281Y244872I-3502J1D01*
G03Y244628I159J-122D01*
G02X402002Y242500I-2781J-2128D01*
G02X401959Y241949I-3502J-4D01*
G01X401952Y241908D01*
X401973Y241828D01*
X402178Y241564D01*
G03X402317Y241488I158J123D01*
G01X402318D01*
G02X405502Y238000I-319J-3488D01*
G01Y237998D01*
G02X405202Y236581I-3502J1D01*
G03Y236419I183J-81D01*
G02X405502Y235002I-3202J-1418D01*
G01Y235000D01*
G02X398498I-3502J0D01*
G01Y235002D01*
G02X398798Y236419I3502J-1D01*
G03Y236581I-183J81D01*
G02X398498Y238000I3202J1418D01*
G02X398541Y238551I3502J4D01*
G01X398548Y238592D01*
X398527Y238672D01*
X398322Y238936D01*
G03X398183Y239012I-158J-123D01*
G01X398182D01*
G02X394998Y242500I319J3488D01*
G37*
G36*
G01X548498Y243500D02*
Y243502D01*
G02X548913Y245156I3502J0D01*
G03Y245344I-176J94D01*
G02X548498Y246998I3087J1654D01*
G01Y247000D01*
G02X555502I3502J0D01*
G01Y246998D01*
G02X555087Y245344I-3502J0D01*
G03Y245156I176J-94D01*
G02X555502Y243500I-3087J-1654D01*
G02X555459Y242949I-3502J-4D01*
G01X555452Y242908D01*
X555473Y242828D01*
X555678Y242564D01*
G03X555817Y242488I158J123D01*
G01X555818D01*
G02X559002Y239000I-319J-3488D01*
G01Y238998D01*
G02X558702Y237581I-3502J1D01*
G03Y237419I183J-81D01*
G02X559002Y236002I-3202J-1418D01*
G01Y236000D01*
G02X551998I-3502J0D01*
G01Y236002D01*
G02X552298Y237419I3502J-1D01*
G03Y237581I-183J81D01*
G02X551998Y239000I3202J1418D01*
G02X552041Y239551I3502J4D01*
G01X552048Y239592D01*
X552027Y239672D01*
X551822Y239936D01*
G03X551683Y240012I-158J-123D01*
G01X551682D01*
G02X548498Y243500I319J3488D01*
G37*
G36*
G01X705978D02*
G02X706404Y245172I3502J-2D01*
G03X706405Y245361I-176J95D01*
G02X705998Y246999I3095J1639D01*
G01Y247000D01*
G02X713002I3502J0D01*
G02X712577Y245328I-3501J0D01*
G03X712576Y245139I176J-95D01*
G02X712984Y243500I-3095J-1641D01*
G02X712940Y242949I-3503J2D01*
G01X712933Y242908D01*
X712954Y242828D01*
X713159Y242564D01*
G03X713298Y242488I158J123D01*
G01X713299D01*
G02X716484Y239000I-317J-3488D01*
G02X716183Y237581I-3503J2D01*
G03Y237419I183J-81D01*
G02X716484Y236000I-3202J-1421D01*
G02X709478I-3503J0D01*
G02X709779Y237419I3503J-2D01*
G03Y237581I-183J81D01*
G02X709478Y239000I3202J1421D01*
G02X709522Y239551I3503J-2D01*
G01X709529Y239592D01*
X709508Y239672D01*
X709303Y239936D01*
G03X709164Y240012I-158J-123D01*
G01X709163D01*
G02X705978Y243500I317J3488D01*
G37*
G36*
G01X238998Y243000D02*
Y243001D01*
G02X239719Y245128I3502J-1D01*
G03Y245372I-159J122D01*
G02X238998Y247499I2781J2128D01*
G01Y247500D01*
G02X246002I3502J0D01*
G01Y247499D01*
G02X245281Y245372I-3502J1D01*
G03Y245128I159J-122D01*
G02X246002Y243000I-2781J-2128D01*
G02X245959Y242449I-3502J-4D01*
G01X245952Y242408D01*
X245973Y242328D01*
X246178Y242064D01*
G03X246317Y241988I158J123D01*
G01X246318D01*
G02X249502Y238500I-319J-3488D01*
G01Y238498D01*
G02X249202Y237081I-3502J1D01*
G03Y236919I183J-81D01*
G02X249502Y235502I-3202J-1418D01*
G01Y235500D01*
G02X242498I-3502J0D01*
G01Y235502D01*
G02X242798Y236919I3502J-1D01*
G03Y237081I-183J81D01*
G02X242498Y238500I3202J1418D01*
G02X242541Y239051I3502J4D01*
G01X242548Y239092D01*
X242527Y239172D01*
X242322Y239436D01*
G03X242183Y239512I-158J-123D01*
G01X242182D01*
G02X238998Y243000I319J3488D01*
G37*
G36*
G01X943886Y562188D02*
X1030500D01*
G02Y522812I0J-19688D01*
G01X943886D01*
G02Y562188I0J19688D01*
G37*
G36*
G01X1140000Y168798D02*
X1139998D01*
G02X1138250Y169266I1J3502D01*
G03X1138050I-100J-173D01*
G02X1136302Y168798I-1749J3034D01*
G01X1136300D01*
G02Y175802I0J3502D01*
G01X1136302D01*
G02X1138050Y175334I-1J-3502D01*
G03X1138250I100J173D01*
G02X1139998Y175802I1749J-3034D01*
G01X1140000D01*
G02Y168798I0J-3502D01*
G37*
G36*
G01X1079500Y181072D02*
G02Y188078I0J3503D01*
G02X1081968Y187060I-1J-3503D01*
G01X1081969Y187059D01*
G03X1082109Y187002I140J143D01*
G01X1082391D01*
G03X1082531Y187059I0J200D01*
G01X1082532Y187060D01*
G02X1085000Y188078I2469J-2485D01*
G02Y181072I0J-3503D01*
G02X1082532Y182090I1J3503D01*
G01X1082531Y182091D01*
G03X1082391Y182148I-140J-143D01*
G01X1082109D01*
G03X1081969Y182091I0J-200D01*
G01X1081968Y182090D01*
G02X1079500Y181072I-2469J2485D01*
G37*
G36*
G01X884000Y286978D02*
G02X885892Y286422I-2J-3503D01*
G03X886108I108J169D01*
G02X888000Y286978I1894J-2947D01*
G02X890917Y285414I0J-3502D01*
G01X890945Y285373D01*
X891033Y285325D01*
X891467D01*
X891555Y285373D01*
X891583Y285414D01*
G02X894500Y286978I2917J-1938D01*
G02Y279972I0J-3503D01*
G02X891583Y281536I0J3502D01*
G01X891555Y281577D01*
X891467Y281625D01*
X891033D01*
X890945Y281577D01*
X890917Y281536D01*
G02X888000Y279972I-2917J1938D01*
G02X886108Y280528I2J3503D01*
G03X885892I-108J-169D01*
G02X884000Y279972I-1894J2947D01*
G02X881083Y281536I0J3502D01*
G01X881055Y281577D01*
X880967Y281625D01*
X880533D01*
X880445Y281577D01*
X880417Y281536D01*
G02X877500Y279972I-2917J1938D01*
G02Y286978I0J3503D01*
G02X880417Y285414I0J-3502D01*
G01X880445Y285373D01*
X880533Y285325D01*
X880967D01*
X881055Y285373D01*
X881083Y285414D01*
G02X884000Y286978I2917J-1938D01*
G37*
G36*
G01X905000D02*
G02X906892Y286422I-2J-3503D01*
G03X907108I108J169D01*
G02X909000Y286978I1894J-2947D01*
G02X911917Y285414I0J-3502D01*
G01X911945Y285373D01*
X912033Y285325D01*
X912467D01*
X912555Y285373D01*
X912583Y285414D01*
G02X915500Y286978I2917J-1938D01*
G02Y279972I0J-3503D01*
G02X912583Y281536I0J3502D01*
G01X912555Y281577D01*
X912467Y281625D01*
X912033D01*
X911945Y281577D01*
X911917Y281536D01*
G02X909000Y279972I-2917J1938D01*
G02X907108Y280528I2J3503D01*
G03X906892I-108J-169D01*
G02X905000Y279972I-1894J2947D01*
G02Y286978I0J3503D01*
G37*
G36*
G01X926998Y315460D02*
G02X934002I3502J0D01*
G01Y315459D01*
G02X933639Y313907I-3502J1D01*
G03Y313731I180J-88D01*
G01X933798Y313404D01*
X933870Y313348D01*
X933916Y313338D01*
G02X936698Y309910I-721J-3428D01*
G02X929694I-3502J0D01*
G01Y309911D01*
G02X930057Y311463I3502J-1D01*
G03Y311639I-180J88D01*
G01X929898Y311966D01*
X929826Y312022D01*
X929780Y312032D01*
G02X926998Y315460I721J3428D01*
G37*
G36*
G01X912758Y337077D02*
G02X916260Y333574I3502J-1D01*
G02X915870Y333596I2J3503D01*
G03X915699Y333532I-23J-199D01*
G01X915449Y333258D01*
X915423Y333167D01*
X915433Y333120D01*
G02X915502Y332425I-3433J-692D01*
G02X915009Y330632I-3502J-1D01*
G03X915036Y330392I172J-102D01*
G02X916002Y327975I-2537J-2415D01*
G02X915621Y326385I-3502J-1D01*
G03X915617Y326211I178J-91D01*
G01X915745Y325927D01*
G03X915877Y325816I182J83D01*
G02X918502Y322425I-878J-3391D01*
G02X911498I-3502J0D01*
G01Y322428D01*
G02X911879Y324015I3502J-2D01*
G03X911883Y324189I-178J91D01*
G01X911755Y324473D01*
G03X911623Y324584I-182J-83D01*
G02X910372Y325194I879J3390D01*
G03X910128I-122J-159D01*
G02X908000Y324472I-2130J2780D01*
G02X905872Y325194I2J3502D01*
G03X905628I-122J-159D01*
G02X903500Y324472I-2130J2780D01*
G02Y331478I0J3503D01*
G02X905628Y330756I-2J-3502D01*
G03X905872I122J159D01*
G02X907999Y331478I2130J-2780D01*
G01X908001D01*
G02X908121Y331475I-28J-3502D01*
G01X908123D01*
G03X908278Y331541I6J200D01*
G01X908513Y331803D01*
X908539Y331887D01*
X908532Y331931D01*
G02X908498Y332425I3468J487D01*
G02X912000Y335928I3502J1D01*
G02X912390Y335906I-2J-3503D01*
G03X912561Y335970I23J199D01*
G01X912811Y336244D01*
X912837Y336335D01*
X912827Y336382D01*
G02X912758Y337077I3433J692D01*
G37*
G36*
G01X593002Y446500D02*
G02X590942Y443308I-3503J0D01*
G03X590834Y443187I82J-182D01*
G02X587500Y440758I-3334J1074D01*
G02X583998Y444260I0J3502D01*
G02X586058Y447452I3503J0D01*
G03X586166Y447573I-82J182D01*
G02X589500Y450002I3334J-1074D01*
G02X593002Y446500I0J-3502D01*
G37*
G36*
G01X940390Y313255D02*
G02X939668Y315385I2781J2130D01*
G02X946674I3503J0D01*
G02X945953Y313258I-3503J2D01*
G03Y313014I159J-122D01*
G02X946674Y310885I-2781J-2128D01*
G02X943172Y307382I-3502J-1D01*
G02X943099Y307383I11J3503D01*
G01X943035Y307384D01*
X942931Y307314D01*
X942752Y306841D01*
X942784Y306719D01*
X942833Y306678D01*
G02X943889Y305132I-2259J-2677D01*
G01X943906Y305083D01*
X943981Y305015D01*
X944362Y304924D01*
G03X944548Y304976I46J195D01*
G02X947000Y305978I2453J-2501D01*
G02Y298972I0J-3503D01*
G02X943686Y301343I1J3503D01*
G01X943669Y301392D01*
X943594Y301460D01*
X943213Y301551D01*
G03X943027Y301499I-46J-195D01*
G02X941174Y300549I-2452J2501D01*
G03X941009Y300337I34J-197D01*
G02X941018Y300075I-3494J-251D01*
G02X940036Y297643I-3503J0D01*
G01X939995Y297601D01*
X939972Y297488D01*
X940121Y297095D01*
G03X940290Y296966I187J70D01*
G01X940291D01*
G02X943141Y295025I-291J-3490D01*
G03X943321Y294914I179J89D01*
G01X943679D01*
G03X943859Y295025I1J200D01*
G02X947000Y296978I3141J-1549D01*
G02Y289974I0J-3502D01*
G02X943859Y291927I0J3502D01*
G03X943679Y292038I-179J-89D01*
G01X943321D01*
G03X943141Y291927I-1J-200D01*
G02X936859I-3141J1550D01*
G03X936679Y292038I-179J-89D01*
G01X936321D01*
G03X936141Y291927I-1J-200D01*
G02X933000Y289974I-3141J1549D01*
G02Y296978I0J3502D01*
G02X936141Y295025I0J-3502D01*
G03X936321Y294914I179J89D01*
G01X936679D01*
G03X936859Y295025I1J200D01*
G02X937480Y295908I3141J-1549D01*
G01X937521Y295950D01*
X937544Y296063D01*
X937395Y296456D01*
G03X937226Y296585I-187J-70D01*
G01X937225D01*
G02X934014Y300075I291J3490D01*
G02X936917Y303526I3503J0D01*
G03X937082Y303738I-34J197D01*
G02X937072Y304000I3493J265D01*
G02X940575Y307502I3503J-1D01*
G01X940646D01*
X940650D01*
X940712Y307501D01*
X940816Y307571D01*
X940995Y308044D01*
X940963Y308166D01*
X940914Y308207D01*
G02X939670Y310885I2258J2677D01*
G02X940390Y313012I3502J0D01*
G03Y313255I-159J122D01*
G37*
G36*
G01X183539Y494498D02*
X183537D01*
G02X182120Y494798I1J3502D01*
G03X181958I-81J-183D01*
G02X180541Y494498I-1418J3202D01*
G01X180539D01*
G02Y501502I0J3502D01*
G01X180541D01*
G02X181958Y501202I-1J-3502D01*
G03X182120I81J183D01*
G02X183537Y501502I1418J-3202D01*
G01X183539D01*
G02Y494498I0J-3502D01*
G37*
G36*
G01X231539D02*
X231537D01*
G02X230120Y494798I1J3502D01*
G03X229958I-81J-183D01*
G02X228541Y494498I-1418J3202D01*
G01X228539D01*
G02Y501502I0J3502D01*
G01X228541D01*
G02X229958Y501202I-1J-3502D01*
G03X230120I81J183D01*
G02X231537Y501502I1418J-3202D01*
G01X231539D01*
G02Y494498I0J-3502D01*
G37*
G36*
G01X279539D02*
X279537D01*
G02X278120Y494798I1J3502D01*
G03X277958I-81J-183D01*
G02X276541Y494498I-1418J3202D01*
G01X276539D01*
G02Y501502I0J3502D01*
G01X276541D01*
G02X277958Y501202I-1J-3502D01*
G03X278120I81J183D01*
G02X279537Y501502I1418J-3202D01*
G01X279539D01*
G02Y494498I0J-3502D01*
G37*
G36*
G01X341019D02*
X341017D01*
G02X339600Y494798I1J3502D01*
G03X339438I-81J-183D01*
G02X338021Y494498I-1418J3202D01*
G01X338019D01*
G02Y501502I0J3502D01*
G01X338021D01*
G02X339438Y501202I-1J-3502D01*
G03X339600I81J183D01*
G02X341017Y501502I1418J-3202D01*
G01X341019D01*
G02Y494498I0J-3502D01*
G37*
G36*
G01X389019D02*
X389017D01*
G02X387600Y494798I1J3502D01*
G03X387438I-81J-183D01*
G02X386021Y494498I-1418J3202D01*
G01X386019D01*
G02Y501502I0J3502D01*
G01X386021D01*
G02X387438Y501202I-1J-3502D01*
G03X387600I81J183D01*
G02X389017Y501502I1418J-3202D01*
G01X389019D01*
G02Y494498I0J-3502D01*
G37*
G36*
G01X437019D02*
X437017D01*
G02X435600Y494798I1J3502D01*
G03X435438I-81J-183D01*
G02X434021Y494498I-1418J3202D01*
G01X434019D01*
G02Y501502I0J3502D01*
G01X434021D01*
G02X435438Y501202I-1J-3502D01*
G03X435600I81J183D01*
G02X437017Y501502I1418J-3202D01*
G01X437019D01*
G02Y494498I0J-3502D01*
G37*
G36*
G01X498500D02*
X498498D01*
G02X497081Y494798I1J3502D01*
G03X496919I-81J-183D01*
G02X495502Y494498I-1418J3202D01*
G01X495500D01*
G02Y501502I0J3502D01*
G01X495502D01*
G02X496919Y501202I-1J-3502D01*
G03X497081I81J183D01*
G02X498498Y501502I1418J-3202D01*
G01X498500D01*
G02Y494498I0J-3502D01*
G37*
G36*
G01X546500D02*
X546498D01*
G02X545081Y494798I1J3502D01*
G03X544919I-81J-183D01*
G02X543502Y494498I-1418J3202D01*
G01X543500D01*
G02Y501502I0J3502D01*
G01X543502D01*
G02X544919Y501202I-1J-3502D01*
G03X545081I81J183D01*
G02X546498Y501502I1418J-3202D01*
G01X546500D01*
G02Y494498I0J-3502D01*
G37*
G36*
G01X594500D02*
X594498D01*
G02X593081Y494798I1J3502D01*
G03X592919I-81J-183D01*
G02X591502Y494498I-1418J3202D01*
G01X591500D01*
G02Y501502I0J3502D01*
G01X591502D01*
G02X592919Y501202I-1J-3502D01*
G03X593081I81J183D01*
G02X594498Y501502I1418J-3202D01*
G01X594500D01*
G02Y494498I0J-3502D01*
G37*
G36*
G01X655981D02*
X655979D01*
G02X654562Y494798I1J3502D01*
G03X654400I-81J-183D01*
G02X652983Y494498I-1418J3202D01*
G01X652981D01*
G02Y501502I0J3502D01*
G01X652983D01*
G02X654400Y501202I-1J-3502D01*
G03X654562I81J183D01*
G02X655979Y501502I1418J-3202D01*
G01X655981D01*
G02Y494498I0J-3502D01*
G37*
G36*
G01X703981D02*
X703979D01*
G02X702562Y494798I1J3502D01*
G03X702400I-81J-183D01*
G02X700983Y494498I-1418J3202D01*
G01X700981D01*
G02Y501502I0J3502D01*
G01X700983D01*
G02X702400Y501202I-1J-3502D01*
G03X702562I81J183D01*
G02X703979Y501502I1418J-3202D01*
G01X703981D01*
G02Y494498I0J-3502D01*
G37*
G36*
G01X751981D02*
X751979D01*
G02X750562Y494798I1J3502D01*
G03X750400I-81J-183D01*
G02X748983Y494498I-1418J3202D01*
G01X748981D01*
G02Y501502I0J3502D01*
G01X748983D01*
G02X750400Y501202I-1J-3502D01*
G03X750562I81J183D01*
G02X751979Y501502I1418J-3202D01*
G01X751981D01*
G02Y494498I0J-3502D01*
G37*
G36*
G01X183539Y514498D02*
X183537D01*
G02X182120Y514798I1J3502D01*
G03X181958I-81J-183D01*
G02X180541Y514498I-1418J3202D01*
G01X180539D01*
G02Y521502I0J3502D01*
G01X180541D01*
G02X181958Y521202I-1J-3502D01*
G03X182120I81J183D01*
G02X183537Y521502I1418J-3202D01*
G01X183539D01*
G02Y514498I0J-3502D01*
G37*
G36*
G01X231539D02*
X231537D01*
G02X230120Y514798I1J3502D01*
G03X229958I-81J-183D01*
G02X228541Y514498I-1418J3202D01*
G01X228539D01*
G02Y521502I0J3502D01*
G01X228541D01*
G02X229958Y521202I-1J-3502D01*
G03X230120I81J183D01*
G02X231537Y521502I1418J-3202D01*
G01X231539D01*
G02Y514498I0J-3502D01*
G37*
G36*
G01X279539D02*
X279537D01*
G02X278120Y514798I1J3502D01*
G03X277958I-81J-183D01*
G02X276541Y514498I-1418J3202D01*
G01X276539D01*
G02Y521502I0J3502D01*
G01X276541D01*
G02X277958Y521202I-1J-3502D01*
G03X278120I81J183D01*
G02X279537Y521502I1418J-3202D01*
G01X279539D01*
G02Y514498I0J-3502D01*
G37*
G36*
G01X341019D02*
X341017D01*
G02X339600Y514798I1J3502D01*
G03X339438I-81J-183D01*
G02X338021Y514498I-1418J3202D01*
G01X338019D01*
G02Y521502I0J3502D01*
G01X338021D01*
G02X339438Y521202I-1J-3502D01*
G03X339600I81J183D01*
G02X341017Y521502I1418J-3202D01*
G01X341019D01*
G02Y514498I0J-3502D01*
G37*
G36*
G01X389019D02*
X389017D01*
G02X387600Y514798I1J3502D01*
G03X387438I-81J-183D01*
G02X386021Y514498I-1418J3202D01*
G01X386019D01*
G02Y521502I0J3502D01*
G01X386021D01*
G02X387438Y521202I-1J-3502D01*
G03X387600I81J183D01*
G02X389017Y521502I1418J-3202D01*
G01X389019D01*
G02Y514498I0J-3502D01*
G37*
G36*
G01X437019D02*
X437017D01*
G02X435600Y514798I1J3502D01*
G03X435438I-81J-183D01*
G02X434021Y514498I-1418J3202D01*
G01X434019D01*
G02Y521502I0J3502D01*
G01X434021D01*
G02X435438Y521202I-1J-3502D01*
G03X435600I81J183D01*
G02X437017Y521502I1418J-3202D01*
G01X437019D01*
G02Y514498I0J-3502D01*
G37*
G36*
G01X498500D02*
X498498D01*
G02X497081Y514798I1J3502D01*
G03X496919I-81J-183D01*
G02X495502Y514498I-1418J3202D01*
G01X495500D01*
G02Y521502I0J3502D01*
G01X495502D01*
G02X496919Y521202I-1J-3502D01*
G03X497081I81J183D01*
G02X498498Y521502I1418J-3202D01*
G01X498500D01*
G02Y514498I0J-3502D01*
G37*
G36*
G01X546500D02*
X546498D01*
G02X545081Y514798I1J3502D01*
G03X544919I-81J-183D01*
G02X543502Y514498I-1418J3202D01*
G01X543500D01*
G02Y521502I0J3502D01*
G01X543502D01*
G02X544919Y521202I-1J-3502D01*
G03X545081I81J183D01*
G02X546498Y521502I1418J-3202D01*
G01X546500D01*
G02Y514498I0J-3502D01*
G37*
G36*
G01X594500D02*
X594498D01*
G02X593081Y514798I1J3502D01*
G03X592919I-81J-183D01*
G02X591502Y514498I-1418J3202D01*
G01X591500D01*
G02Y521502I0J3502D01*
G01X591502D01*
G02X592919Y521202I-1J-3502D01*
G03X593081I81J183D01*
G02X594498Y521502I1418J-3202D01*
G01X594500D01*
G02Y514498I0J-3502D01*
G37*
G36*
G01X655981D02*
X655979D01*
G02X654562Y514798I1J3502D01*
G03X654400I-81J-183D01*
G02X652983Y514498I-1418J3202D01*
G01X652981D01*
G02Y521502I0J3502D01*
G01X652983D01*
G02X654400Y521202I-1J-3502D01*
G03X654562I81J183D01*
G02X655979Y521502I1418J-3202D01*
G01X655981D01*
G02Y514498I0J-3502D01*
G37*
G36*
G01X703981D02*
X703979D01*
G02X702562Y514798I1J3502D01*
G03X702400I-81J-183D01*
G02X700983Y514498I-1418J3202D01*
G01X700981D01*
G02Y521502I0J3502D01*
G01X700983D01*
G02X702400Y521202I-1J-3502D01*
G03X702562I81J183D01*
G02X703979Y521502I1418J-3202D01*
G01X703981D01*
G02Y514498I0J-3502D01*
G37*
G36*
G01X751981D02*
X751979D01*
G02X750562Y514798I1J3502D01*
G03X750400I-81J-183D01*
G02X748983Y514498I-1418J3202D01*
G01X748981D01*
G02Y521502I0J3502D01*
G01X748983D01*
G02X750400Y521202I-1J-3502D01*
G03X750562I81J183D01*
G02X751979Y521502I1418J-3202D01*
G01X751981D01*
G02Y514498I0J-3502D01*
G37*
G36*
G01X1127490Y192288D02*
G02X1125918Y191916I-1571J3130D01*
G02Y198920I0J3502D01*
G02X1127325Y198625I0J-3503D01*
G03X1127496Y198630I80J183D01*
G02X1129068Y199002I1571J-3130D01*
G02X1129467Y198980I7J-3502D01*
G03X1129680Y199115I23J199D01*
G02X1133000Y201502I3320J-1115D01*
G02Y194498I0J-3502D01*
G02X1132601Y194520I-7J3502D01*
G03X1132388Y194385I-23J-199D01*
G02X1129068Y191998I-3320J1115D01*
G02X1127661Y192293I0J3503D01*
G03X1127490Y192288I-80J-183D01*
G37*
G36*
G01X1098818Y206997D02*
G02X1100000Y207202I1181J-3297D01*
G02Y200198I0J-3502D01*
G02X1098818Y200403I-1J3502D01*
G03X1098682I-68J-188D01*
G02X1097500Y200198I-1181J3297D01*
G02Y207202I0J3502D01*
G02X1098682Y206997I1J-3502D01*
G03X1098818I68J188D01*
G37*
G54D55*
X1158200Y137700D03*
X1092000Y82500D03*
X1084325Y130197D03*
G54D49*
X247441Y305975D03*
X404921D03*
X562402D03*
X719883D03*
X1024340Y146600D03*
X184349Y212651D03*
X183815Y220903D03*
X809500Y259430D03*
X797854Y259539D03*
X1094024Y179500D03*
X1120200Y176500D03*
X1129000Y157000D03*
Y166500D03*
Y176500D03*
X748075Y366500D03*
X943885Y352385D03*
X933196Y353360D03*
X941035Y344474D03*
X933357Y344843D03*
X545063Y340339D03*
X940000Y283800D03*
X901063Y352340D03*
X923740Y345500D03*
X914500Y292000D03*
X905941Y306500D03*
X904500Y292000D03*
X905941Y320366D03*
X549500Y445024D03*
X538780Y445025D03*
X313571Y340552D03*
X430019Y444260D03*
X381299Y445025D03*
X926000Y283475D03*
X290720Y340338D03*
X173265Y340552D03*
X875000Y347273D03*
X893363Y298740D03*
X883000Y293925D03*
X432019Y452025D03*
X880000Y312855D03*
X447255Y340339D03*
X223819Y445025D03*
X473095Y340339D03*
X696261Y445024D03*
G54D50*
X1226024Y286929D03*
G54D54*
X48780Y329724D03*
G54D57*
X779981Y220315D03*
X823981D03*
X357000D03*
X735981D03*
X312500D03*
X268000D03*
X428500D03*
X472500D03*
X516500D03*
X578500D03*
X622500D03*
X666500D03*
G54D58*
X233224Y539000D03*
X705666D03*
X596185D03*
X548185D03*
X500185D03*
X438704D03*
X657666D03*
X390704D03*
X342704D03*
X753666D03*
X281224D03*
X185224D03*
G54D51*
X19922Y367716D03*
Y214173D03*
G54D52*
X964460Y16950D03*
X175000Y100500D03*
X1271654Y636929D03*
X619685D03*
G54D53*
X108858Y99724D03*
Y482205D03*
G54D48*
X1226024Y174429D03*
X980059Y149408D03*
G54D56*
X249252Y129685D03*
X529252D03*
X665059Y149408D03*
X1226024Y399429D03*
G54D10*
X3005Y19808D03*
Y34808D03*
Y59808D03*
X7595Y128373D03*
X3005Y145238D03*
Y165238D03*
Y185238D03*
Y205238D03*
Y225238D03*
Y245238D03*
Y265238D03*
Y285238D03*
Y305238D03*
Y325238D03*
Y345238D03*
Y365238D03*
Y385238D03*
Y405238D03*
Y425238D03*
Y445238D03*
X3023Y524312D03*
Y549312D03*
X4540Y566003D03*
X34582Y3004D03*
X14811Y3732D03*
X12767Y72072D03*
X27271Y127298D03*
X19558Y454589D03*
X9913Y510026D03*
X20498Y575739D03*
X54582Y3004D03*
X63436Y353962D03*
X39549Y454916D03*
X40498Y575739D03*
X60498D03*
X94582Y3004D03*
X74582D03*
X80498Y575739D03*
X114582Y3004D03*
X108600Y258560D03*
X111600D03*
X108600Y261560D03*
X111600D03*
X108600Y255560D03*
X111600D03*
X100498Y575739D03*
X120498D03*
X154582Y3004D03*
X134582D03*
X153480Y213350D03*
X150634Y219063D03*
X155140Y240230D03*
X154840Y244730D03*
X155034Y228063D03*
Y224563D03*
X152334Y223063D03*
Y226563D03*
Y230063D03*
X155034Y231563D03*
X140498Y575739D03*
X174582Y3004D03*
X172934Y219110D03*
X184349Y212651D03*
X183900Y216830D03*
X178265Y213443D03*
X175976Y218775D03*
X172712Y222263D03*
X183815Y220903D03*
X165840Y247805D03*
X169840D03*
X166068Y238749D03*
X173869Y228168D03*
X175481Y225183D03*
X160017Y237764D03*
X161400Y323200D03*
X173265Y340552D03*
X183539Y518000D03*
X180539Y498000D03*
X183539D03*
X180539Y518000D03*
X214582Y3004D03*
X194582D03*
X189760Y242100D03*
Y245100D03*
X192760Y242100D03*
Y245100D03*
X195760Y242100D03*
Y245100D03*
X198760Y242100D03*
Y245100D03*
X201760Y242100D03*
Y245100D03*
X203575Y297500D03*
X212925Y315500D03*
X234582Y3004D03*
X246000Y238500D03*
X242500Y243000D03*
Y247500D03*
X218500Y309500D03*
X226975D03*
X235975D03*
X230425Y313605D03*
X221425Y313000D03*
X223819Y445025D03*
X231539Y518000D03*
X228539Y498000D03*
X231539D03*
X228539Y518000D03*
X254582Y3004D03*
X246000Y235500D03*
X247441Y305975D03*
X294582Y3004D03*
X274582D03*
X297000Y206000D03*
Y203500D03*
Y198500D03*
Y196000D03*
X290720Y340338D03*
X279539Y518000D03*
X276539Y498000D03*
X279539D03*
X276539Y518000D03*
X314582Y3004D03*
X318500Y206000D03*
Y203500D03*
Y198500D03*
Y196000D03*
X313571Y340552D03*
X354582Y3004D03*
X334582D03*
X340000Y206000D03*
Y203500D03*
Y198500D03*
Y196000D03*
X361500Y206000D03*
Y203500D03*
Y198500D03*
Y196000D03*
X361000Y305975D03*
X341019Y518000D03*
X338019Y498000D03*
X341019D03*
X338019Y518000D03*
X374582Y3004D03*
X383000Y206000D03*
Y203500D03*
Y198500D03*
Y196000D03*
X375500Y309500D03*
X383975D03*
X382963Y316400D03*
Y313750D03*
X381299Y445025D03*
X389019Y518000D03*
X386019Y498000D03*
X389019D03*
X386019Y518000D03*
X414582Y3004D03*
X394582D03*
X404500Y206000D03*
Y203500D03*
Y198500D03*
Y196000D03*
X402000Y235000D03*
Y238000D03*
X398500Y247000D03*
Y242500D03*
X404921Y305975D03*
X392975Y309500D03*
X434582Y3004D03*
X426000Y206000D03*
Y203500D03*
Y198500D03*
Y196000D03*
X447255Y340339D03*
X430019Y444260D03*
X432019Y452025D03*
X437019Y518000D03*
X434019Y498000D03*
X437019D03*
X434019Y518000D03*
X474582Y3004D03*
X454582D03*
X473095Y340339D03*
X494582Y3004D03*
X498500Y498000D03*
X495500D03*
X498500Y518000D03*
X495500D03*
X534582Y3004D03*
X514582D03*
X518575Y295500D03*
X533475Y310500D03*
X539619Y316400D03*
Y313400D03*
X538780Y445025D03*
X554582Y3004D03*
X555500Y239000D03*
Y236000D03*
X552000Y243500D03*
Y247000D03*
X562402Y305975D03*
X542475Y310500D03*
X551475D03*
X545063Y340339D03*
X549500Y445024D03*
X546500Y498000D03*
X543500D03*
X546500Y518000D03*
X543500D03*
X594582Y3004D03*
X574582D03*
X587500Y444260D03*
X589500Y446500D03*
X594500Y498000D03*
X591500D03*
X594500Y518000D03*
X591500D03*
X614582Y3004D03*
X604500Y205500D03*
Y203000D03*
Y198000D03*
Y195500D03*
X626000Y205500D03*
Y203000D03*
Y198000D03*
Y195500D03*
X654582Y3004D03*
X634582D03*
X640900Y42300D03*
X647999Y33000D03*
X638200Y44000D03*
Y46500D03*
X641100Y48100D03*
X647500Y205500D03*
Y203000D03*
Y198000D03*
Y195500D03*
X655981Y518000D03*
Y498000D03*
X652981D03*
Y518000D03*
X674582Y3004D03*
X690075Y39500D03*
X669000Y205500D03*
Y203000D03*
Y198000D03*
Y195500D03*
X676075Y299600D03*
X680400Y310500D03*
X714582Y3004D03*
X694582D03*
X703740Y41000D03*
X707000Y32000D03*
X694425Y29500D03*
X703740Y54118D03*
X690500Y205500D03*
Y203000D03*
Y198000D03*
Y195500D03*
X711990D03*
Y198000D03*
Y203000D03*
Y205500D03*
X709500Y247000D03*
X709481Y243500D03*
X712981Y236000D03*
Y239000D03*
X716100Y255987D03*
X700040Y258960D03*
X694406Y295500D03*
X690956Y310500D03*
X699956D03*
X708956D03*
X697100Y313400D03*
X704400Y358600D03*
X702200Y356000D03*
X697900Y352500D03*
X707750Y358750D03*
X696261Y445024D03*
X703981Y518000D03*
Y498000D03*
X700981D03*
Y518000D03*
X734582Y3004D03*
X747160Y30000D03*
Y38500D03*
Y64000D03*
Y47000D03*
Y55500D03*
X733490Y195500D03*
Y198000D03*
Y203000D03*
Y205500D03*
X719883Y305975D03*
X724000Y294500D03*
X742500Y328500D03*
Y324500D03*
Y334500D03*
X735075Y326000D03*
Y336000D03*
X731925D03*
X732000Y326000D03*
X742500Y361500D03*
X742000Y341500D03*
X742500Y347700D03*
Y353200D03*
X774582Y3004D03*
X754582D03*
X750300Y27200D03*
X752560Y30100D03*
X749760D03*
X752560Y38600D03*
X749760D03*
X752560Y64100D03*
X749760D03*
X752560Y47100D03*
X749760D03*
X752560Y55600D03*
X749760D03*
X754000Y353500D03*
Y356957D03*
X748075Y366500D03*
X748981Y498000D03*
X751981D03*
Y518000D03*
X748981D03*
X794582Y3004D03*
X797854Y259539D03*
X803900Y279425D03*
X803500Y259525D03*
X784855Y265184D03*
X790000Y259612D03*
X794900Y265979D03*
X806000Y265075D03*
X806500Y285500D03*
X800575Y338000D03*
X779100Y326820D03*
X798400Y323900D03*
X786500Y316700D03*
X793800Y323880D03*
X781500Y362700D03*
X803000Y357000D03*
Y346500D03*
X802975Y362000D03*
X792000Y358000D03*
X834582Y3004D03*
X814582D03*
X809500Y259430D03*
X808500Y272925D03*
X831000Y260500D03*
X836000D03*
X826000Y260525D03*
X831000Y270500D03*
X808500Y276075D03*
X836000Y270500D03*
X826000Y270525D03*
X833500Y268575D03*
X821000Y270525D03*
X816000D03*
X827602Y283500D03*
X836500Y302500D03*
X814500Y293000D03*
X811500Y329000D03*
X815500D03*
X823500D03*
X819500Y318500D03*
X808425Y334000D03*
X831750Y318250D03*
X813975Y362000D03*
X829500Y354925D03*
X827000Y360475D03*
X811575Y344000D03*
X827000Y352500D03*
X808425Y344000D03*
X854582Y3004D03*
X863600Y208900D03*
X841000Y270500D03*
X846000Y270525D03*
X851000D03*
X856000D03*
X843500Y268575D03*
X853500D03*
X850750Y250750D03*
X853000Y303500D03*
X861600Y304600D03*
X845000Y303000D03*
X865000Y313200D03*
X848500Y335800D03*
X839692Y329592D03*
X854825Y330925D03*
X850500Y360075D03*
Y366000D03*
X847500D03*
X856500D03*
X859500D03*
X865500D03*
X850500Y356925D03*
X843843Y354342D03*
X864500Y358500D03*
X894582Y3004D03*
X874582D03*
X868000Y271500D03*
X894500Y283475D03*
X884000D03*
X877500D03*
X893363Y298740D03*
X883000Y293925D03*
X867000Y291260D03*
X870000Y304525D03*
X875000D03*
X880000D03*
X888000Y283475D03*
X870000Y312788D03*
X880000Y312855D03*
X875000Y347273D03*
X877500Y366000D03*
X874500D03*
X884000D03*
X887000D03*
X893500D03*
X868500D03*
X878000Y358475D03*
X883000Y358500D03*
X874000Y358475D03*
X885500Y352925D03*
X869000Y360500D03*
X914582Y3004D03*
X915500Y283475D03*
X914500Y292000D03*
X905000Y283475D03*
X905941Y306500D03*
X909000Y283475D03*
X904500Y292000D03*
X912500Y327975D03*
X916260Y337077D03*
X908000Y327975D03*
X915000Y322425D03*
X912000Y332425D03*
X905941Y320366D03*
X903500Y327975D03*
X896500Y366000D03*
X906000D03*
X903000D03*
X912500D03*
X915500D03*
X922000D03*
X901063Y352340D03*
X916260Y355000D03*
X910992Y361075D03*
X920000Y355525D03*
X923740Y345500D03*
X934582Y3004D03*
X940575Y304000D03*
X933000Y293476D03*
X940000D03*
X947000D03*
X926000Y283475D03*
X937516Y300075D03*
X947000Y302475D03*
X940000Y283800D03*
X933196Y309910D03*
X930500Y315460D03*
X943172Y310885D03*
X943171Y315385D03*
X935516Y361075D03*
X925000Y366000D03*
X944000D03*
X941000D03*
X934500D03*
X950500D03*
X953500D03*
X931500D03*
X927000Y361075D03*
X941035Y344474D03*
X927000Y357925D03*
X943885Y352385D03*
X933357Y344843D03*
X933196Y353360D03*
X940498Y575739D03*
X974582Y3004D03*
X954582D03*
X960498Y575739D03*
X980498D03*
X994582Y3004D03*
X1000498Y575739D03*
X1034582Y3004D03*
X1014582D03*
X1022575Y100925D03*
Y115500D03*
X1034500Y145000D03*
X1037000Y146300D03*
X1037500Y142000D03*
X1036500Y153500D03*
X1043936Y145745D03*
X1019040Y157310D03*
X1019030Y160330D03*
X1022168Y155877D03*
Y161783D03*
X1017909Y151424D03*
X1017837Y154280D03*
X1024340Y146600D03*
X1016614Y187267D03*
Y190267D03*
X1036500Y172000D03*
Y163000D03*
X1039016Y189075D03*
Y183027D03*
X1039538Y179208D03*
X1039016Y185925D03*
X1022000Y171200D03*
X1019700Y166600D03*
X1016614Y197767D03*
X1020498Y575739D03*
X1040498D03*
X1054582Y3004D03*
X1057525Y130500D03*
X1049356Y143900D03*
X1047159Y141487D03*
X1054500Y148500D03*
X1048000Y153500D03*
X1057525Y134000D03*
Y138600D03*
X1073154Y140800D03*
X1057500Y155877D03*
X1070715Y146500D03*
X1063500Y159814D03*
X1070715Y178585D03*
X1048000Y172000D03*
Y163000D03*
X1060500Y164500D03*
X1062500Y191500D03*
X1067000D03*
X1070000D03*
X1058000D03*
X1053830Y191670D03*
X1067701Y270442D03*
X1067679Y317942D03*
X1067707Y365442D03*
X1067531Y412942D03*
X1067730Y460352D03*
X1067866Y507629D03*
X1060498Y575739D03*
X1094582Y3004D03*
X1074582D03*
X1092000Y82500D03*
X1087000Y100000D03*
X1073200Y90900D03*
X1077200D03*
X1084325Y130197D03*
X1094493Y151856D03*
X1073154Y137800D03*
X1082000Y143600D03*
X1092000Y159500D03*
X1094500Y143144D03*
X1084401Y159260D03*
X1094024Y179500D03*
X1085000Y184575D03*
X1079500D03*
X1085525Y167500D03*
Y171000D03*
Y174500D03*
Y164000D03*
X1087500Y198000D03*
Y201000D03*
X1097500Y203700D03*
X1100000D03*
X1073500Y191500D03*
X1086500Y356000D03*
X1090500Y376500D03*
X1090443Y417343D03*
X1086500Y403500D03*
X1080498Y575739D03*
X1100498D03*
X1114582Y3004D03*
X1115800Y126600D03*
X1130125Y135940D03*
X1126075Y135973D03*
X1121238Y144500D03*
X1108500Y136500D03*
X1104500Y136524D03*
X1120524Y138457D03*
X1129000Y157000D03*
X1120200D03*
X1115425Y138925D03*
X1119000Y189500D03*
X1111100Y163749D03*
X1123500Y187000D03*
X1108000Y172000D03*
X1113368Y171619D03*
X1110800Y170000D03*
X1113129Y165719D03*
X1114500Y188700D03*
X1120200Y176500D03*
Y166500D03*
X1129000D03*
Y176500D03*
X1108821Y166800D03*
X1125918Y195418D03*
X1129068Y195500D03*
X1133000Y198000D03*
X1117206Y231741D03*
X1117290Y224241D03*
X1106189D03*
X1106106Y231741D03*
X1120498Y575739D03*
X1154582Y3004D03*
X1134582D03*
X1141500Y124425D03*
Y120500D03*
Y134575D03*
X1158200Y137700D03*
X1136300Y161100D03*
X1140000D03*
X1152781Y165719D03*
X1136300Y172300D03*
X1140000D03*
X1140336Y183560D03*
X1143490D03*
X1158000Y179000D03*
X1140498Y575739D03*
X1160498D03*
X1174582Y3004D03*
X1183021Y165952D03*
X1185521D03*
X1188600Y166000D03*
X1188618Y162782D03*
X1185521Y162952D03*
X1183021D03*
X1180521D03*
Y165952D03*
X1177521D03*
Y162952D03*
X1167600Y184500D03*
Y180500D03*
X1174500Y214000D03*
Y211000D03*
Y208000D03*
Y205000D03*
X1171500D03*
Y208000D03*
Y211000D03*
Y214000D03*
X1179651Y305942D03*
Y309942D03*
X1165070Y328750D03*
X1193411D03*
X1179411Y334250D03*
Y337750D03*
Y330750D03*
Y327250D03*
X1180986Y349234D03*
X1177836D03*
X1179877Y452442D03*
Y448442D03*
X1165190Y471250D03*
X1179500Y476750D03*
Y480250D03*
Y469750D03*
Y473250D03*
X1181075Y491734D03*
X1177925D03*
X1180498Y575739D03*
X1214582Y3004D03*
X1194582D03*
X1193840Y471250D03*
X1200498Y575739D03*
X1220498D03*
X1234582Y3004D03*
X1240498Y575739D03*
X1277657Y4128D03*
X1254582Y3004D03*
X1260498Y575739D03*
X1279438Y573806D03*
X1286766Y12634D03*
X1288331Y30962D03*
Y70962D03*
Y50962D03*
Y90962D03*
Y130962D03*
Y110962D03*
Y150962D03*
Y190962D03*
Y170962D03*
Y210962D03*
Y230962D03*
Y270962D03*
Y250962D03*
Y290962D03*
Y330962D03*
Y310962D03*
Y350962D03*
Y390962D03*
Y370962D03*
Y410962D03*
Y450962D03*
Y430962D03*
Y470962D03*
Y510962D03*
Y490962D03*
Y530962D03*
X1287616Y563889D03*
X1288331Y550962D03*
G54D40*
X943225Y228000D03*
X985225Y542500D03*
G54D12*
X72836Y47244D03*
Y535433D03*
X466536Y47244D03*
X860237D03*
X943225Y228000D03*
X985225Y542500D03*
G54D31*
X268000Y220315D03*
X312500D03*
X357000D03*
X428500D03*
X472500D03*
X516500D03*
X578500D03*
X622500D03*
X666500D03*
X735981D03*
X779981D03*
X823981D03*
G54D26*
X185224Y539000D03*
X233224D03*
X281224D03*
X342704D03*
X390704D03*
X438704D03*
X500185D03*
X548185D03*
X596185D03*
X657666D03*
X705666D03*
X753666D03*
G54D16*
X33780Y334724D03*
Y314724D03*
X38780Y319724D03*
Y329724D03*
Y339724D03*
X33780Y344724D03*
X38780Y349724D03*
X48780Y319724D03*
Y329724D03*
Y339724D03*
X43780Y314724D03*
Y324724D03*
Y334724D03*
X48780Y349724D03*
X43780Y344724D03*
G54D20*
X123000Y414500D03*
X119500D03*
Y411500D03*
X123000D03*
X119500Y408500D03*
X123000D03*
X119500Y417500D03*
X123000D03*
X119500Y420500D03*
X123000D03*
X115700Y420600D03*
Y417600D03*
Y408600D03*
Y411600D03*
Y414600D03*
X123000Y426600D03*
X119500D03*
X123000Y423600D03*
X119500D03*
X115700Y423700D03*
Y426700D03*
X168939Y498000D03*
X171939D03*
X216939D03*
X219939D03*
X264939D03*
X267939D03*
X326419D03*
X329419D03*
X374419D03*
X377419D03*
X422419D03*
X425419D03*
X483900D03*
X486900D03*
X531900D03*
X534900D03*
X582900D03*
X579900D03*
X644381D03*
X641381D03*
X692381D03*
X689381D03*
X740381D03*
X737381D03*
X848075Y306500D03*
X911776Y507184D03*
Y510184D03*
Y501184D03*
Y504184D03*
X923595Y498461D03*
X920595D03*
X920542Y504184D03*
X923542D03*
X920542Y501184D03*
X923542D03*
Y510184D03*
X920542D03*
X923542Y507184D03*
X920542D03*
Y513184D03*
X923542D03*
X911829Y498461D03*
X914829D03*
X917595D03*
X917542Y504184D03*
Y501184D03*
Y510184D03*
Y507184D03*
Y513184D03*
X914776D03*
Y507184D03*
Y510184D03*
Y501184D03*
Y504184D03*
X911776Y513184D03*
X920542Y516184D03*
X923542D03*
X917542D03*
X914776D03*
X911776D03*
X917596Y519014D03*
X914830D03*
X911830D03*
X923596D03*
X920596D03*
X1080418Y373600D03*
X1159710Y306037D03*
X1156710D03*
X1159710Y303037D03*
X1156710D03*
X1159710Y300037D03*
X1156710D03*
X1159710Y297037D03*
X1156710D03*
Y294037D03*
X1159710D03*
Y309037D03*
X1156710D03*
X1159710Y312037D03*
X1156710D03*
X1159710Y321037D03*
X1156710D03*
X1159710Y318037D03*
X1156710D03*
X1159710Y315037D03*
X1156710D03*
X1159799Y448537D03*
X1156799D03*
X1159799Y445537D03*
X1156799D03*
X1159799Y442537D03*
X1156799D03*
X1159799Y439537D03*
X1156799D03*
Y436537D03*
X1159799D03*
Y454537D03*
X1156799D03*
X1159799Y451537D03*
X1156799D03*
X1159799Y457537D03*
X1156799D03*
X1159799Y463537D03*
X1156799D03*
X1159799Y460537D03*
X1156799D03*
X1162710Y306037D03*
Y303037D03*
Y300037D03*
Y297037D03*
Y294037D03*
Y309037D03*
Y312037D03*
Y321037D03*
Y318037D03*
Y315037D03*
X1162799Y448537D03*
Y445537D03*
Y442537D03*
Y439537D03*
Y436537D03*
Y454537D03*
Y451537D03*
Y457537D03*
Y463537D03*
Y460537D03*
G54D27*
X185260Y205350D03*
Y208350D03*
X799655Y474684D03*
Y480503D03*
Y477684D03*
X802655Y474684D03*
Y480503D03*
Y477684D03*
X805655Y474684D03*
Y480503D03*
Y477684D03*
X802655Y483503D03*
X805709Y486332D03*
X805655Y483503D03*
X796655Y474684D03*
Y480503D03*
Y477684D03*
X796709Y486332D03*
X796655Y483503D03*
X799709Y486332D03*
X799655Y483503D03*
X802709Y486332D03*
X825941Y339560D03*
X835610Y355590D03*
X817709Y486332D03*
X817655Y483503D03*
X808655Y474684D03*
Y480503D03*
Y477684D03*
X811655Y474684D03*
Y480503D03*
Y477684D03*
X814655D03*
Y480503D03*
Y474684D03*
X808709Y486332D03*
X808655Y483503D03*
X811709Y486332D03*
X811655Y483503D03*
X814655D03*
X814709Y486332D03*
X817655Y474684D03*
Y480503D03*
Y477684D03*
X841000Y260525D03*
X856257Y474684D03*
Y480503D03*
Y477684D03*
X859257Y474684D03*
Y480503D03*
Y477684D03*
X862257Y474684D03*
Y480503D03*
Y477684D03*
X859257Y483503D03*
X862311Y486332D03*
X862257Y483503D03*
X853257Y474684D03*
Y480503D03*
Y477684D03*
X853311Y486332D03*
X853257Y483503D03*
X856311Y486332D03*
X856257Y483503D03*
X859311Y486332D03*
X1070400Y123200D03*
X1067600D03*
X1111452Y544000D03*
Y541000D03*
X1114452Y544000D03*
Y541000D03*
Y538000D03*
X1111452D03*
X1120669Y544000D03*
Y541000D03*
X1123669Y544000D03*
Y541000D03*
Y538000D03*
X1120669D03*
X1114452Y553000D03*
X1111452D03*
X1114452Y550000D03*
X1111452D03*
X1114452Y547000D03*
X1111452D03*
X1123669Y553000D03*
X1120669D03*
X1123669Y550000D03*
X1120669D03*
X1123669Y547000D03*
X1120669D03*
G54D28*
X208071Y267204D03*
X200197D03*
X215945D03*
X231693D03*
X223819D03*
X239567D03*
X247441D03*
X357677D03*
X365551D03*
X373425D03*
X389173D03*
X381299D03*
X404921D03*
X397047D03*
X523032D03*
X515158D03*
X530906D03*
X538780D03*
X546654D03*
X562402D03*
X554528D03*
X680513D03*
X672639D03*
X688387D03*
X704135D03*
X696261D03*
X712009D03*
X719883D03*
G54D29*
X193819Y477204D03*
X223819D03*
X351299D03*
X381299D03*
X508780D03*
X538780D03*
X666261D03*
X696261D03*
G54D34*
X296752Y129685D03*
Y139685D03*
Y149685D03*
Y159685D03*
X331752Y129685D03*
X306752D03*
X331752Y139685D03*
Y149685D03*
Y159685D03*
X306752Y139685D03*
Y149685D03*
Y159685D03*
X341752Y129685D03*
Y139685D03*
Y149685D03*
Y159685D03*
X376752Y129685D03*
X366752D03*
X376752Y139685D03*
Y149685D03*
Y159685D03*
X366752Y139685D03*
Y149685D03*
Y159685D03*
X812559Y119408D03*
Y129408D03*
X822559Y119408D03*
Y129408D03*
X832559Y119408D03*
Y129408D03*
X812559Y149408D03*
X822559Y139408D03*
Y149408D03*
X832559Y139408D03*
Y149408D03*
X1226024Y286929D03*
X1236024D03*
X1246024D03*
X1256024D03*
G54D41*
X1011000Y98000D03*
Y118000D03*
X1161000Y90400D03*
X1151000D03*
X1171000D03*
G54D38*
X766498Y602542D03*
X766604Y630687D03*
X766498Y612542D03*
X766604Y640687D03*
X1082833Y602542D03*
Y612542D03*
Y630687D03*
Y640687D03*
G54D35*
X411752Y129685D03*
X401752D03*
X411752Y139685D03*
Y149685D03*
Y159685D03*
X401752Y139685D03*
Y149685D03*
Y159685D03*
X446752Y129685D03*
X436752D03*
X446752Y139685D03*
Y149685D03*
Y159685D03*
X436752Y139685D03*
Y149685D03*
Y159685D03*
X481752Y129685D03*
X471752D03*
X481752Y139685D03*
Y149685D03*
Y159685D03*
X471752Y139685D03*
Y149685D03*
Y159685D03*
X1226024Y221929D03*
X1236024D03*
X1246024D03*
X1226024Y231929D03*
X1236024D03*
X1246024D03*
X1226024Y256929D03*
X1236024D03*
X1246024D03*
X1226024Y266929D03*
X1236024D03*
X1246024D03*
X1226024Y306929D03*
X1236024D03*
X1246024D03*
X1226024Y316929D03*
X1236024D03*
X1246024D03*
X1226024Y341929D03*
X1236024D03*
X1246024D03*
X1226024Y351929D03*
X1236024D03*
X1246024D03*
X1256024Y221929D03*
Y231929D03*
Y256929D03*
Y266929D03*
Y306929D03*
Y316929D03*
Y341929D03*
Y351929D03*
G54D24*
X178819Y277204D03*
X193819D03*
X253819D03*
X268819D03*
X336299D03*
X351299D03*
X411299D03*
X426299D03*
X493780D03*
X508780D03*
X568780D03*
X583780D03*
X651261D03*
X666261D03*
X726261D03*
X741261D03*
G54D42*
X1011000Y108000D03*
G54D25*
X165539Y539000D03*
X213539D03*
X261539D03*
X323019D03*
X371019D03*
X419019D03*
X480500D03*
X528500D03*
X576500D03*
X637981D03*
X685981D03*
X733981D03*
G54D44*
X1096017Y635687D03*
G54D43*
Y607542D03*
G54D13*
X118111Y47244D03*
Y535433D03*
X511811Y47244D03*
X905512D03*
G54D11*
X19685Y-614173D03*
Y636929D03*
X619685D03*
X1271654Y-614173D03*
Y636929D03*
G54D14*
X19922Y214173D03*
Y367716D03*
G54D22*
X175000Y100500D03*
X877510Y558620D03*
X964460Y16950D03*
G54D19*
X82795Y99724D03*
Y482205D03*
G54D30*
X249252Y129685D03*
X529252D03*
X665059Y149408D03*
X980059D03*
X1226024Y174429D03*
Y399429D03*
G54D18*
X60630Y99724D03*
Y482205D03*
X108858Y99724D03*
Y482205D03*
G54D23*
X182260Y197050D03*
X179460D03*
X176560D03*
X174660Y205850D03*
Y202650D03*
X167660Y213050D03*
X164760D03*
X167660Y209850D03*
X164760D03*
X805323Y408150D03*
Y405150D03*
X799323D03*
Y408150D03*
X802323Y405150D03*
Y408150D03*
X796600Y408097D03*
Y405097D03*
X802323Y416916D03*
X799323D03*
X805323D03*
X802323Y413916D03*
X799323D03*
X805323D03*
Y411150D03*
X799323D03*
X802323D03*
X796600Y411097D03*
Y413863D03*
Y416863D03*
X811323Y405150D03*
Y408150D03*
X808323D03*
Y405150D03*
Y416916D03*
X811323D03*
X808323Y413916D03*
X811323D03*
Y411150D03*
X808323D03*
X817153Y408096D03*
Y405096D03*
X814323Y405150D03*
Y408150D03*
Y416916D03*
X817153Y416862D03*
X814323Y413916D03*
X817153Y413862D03*
Y411096D03*
X814323Y411150D03*
X850390Y385878D03*
X847390D03*
X859253D03*
X856253D03*
X865542Y385771D03*
X859342Y413916D03*
X856342D03*
X865342D03*
X862342D03*
Y411150D03*
X865342D03*
X856342D03*
X859342D03*
X853619Y411097D03*
Y413863D03*
Y416863D03*
X862342Y408150D03*
Y405150D03*
X865342Y408150D03*
Y405150D03*
X856342D03*
Y408150D03*
X859342Y405150D03*
Y408150D03*
X853619Y408097D03*
Y405097D03*
X859342Y416916D03*
X856342D03*
X865342D03*
X862342D03*
X893091Y385771D03*
X874405D03*
X877405D03*
X868542D03*
X884228D03*
X887228D03*
X868342Y416916D03*
X871342D03*
X868342Y413916D03*
X871342D03*
Y411150D03*
X868342D03*
X874172Y408096D03*
Y405096D03*
Y416862D03*
Y413862D03*
Y411096D03*
X871342Y405150D03*
Y408150D03*
X868342Y405150D03*
Y408150D03*
X896091Y385771D03*
X912525Y385877D03*
X906662D03*
X903662D03*
X922454Y385771D03*
X915525Y385877D03*
X925454Y385771D03*
X944247Y385877D03*
X941247D03*
X931317Y385771D03*
X934317D03*
X950110Y385877D03*
X953110D03*
X1066500Y538000D03*
Y541000D03*
X1069500D03*
X1066500Y544000D03*
X1069500D03*
Y538000D03*
Y547000D03*
Y550000D03*
X1066500Y547000D03*
Y550000D03*
Y553000D03*
X1069500D03*
X1097100Y35582D03*
Y38582D03*
X1099600D03*
Y35582D03*
X1102100D03*
Y38582D03*
X1096961Y18126D03*
Y21126D03*
X1099461D03*
Y18126D03*
X1101961D03*
Y21126D03*
X1097101Y53737D03*
Y56737D03*
X1099601D03*
Y53737D03*
X1102101D03*
Y56737D03*
X1125170Y35582D03*
Y38582D03*
X1127670D03*
Y35582D03*
X1130170D03*
Y38582D03*
X1104600Y35582D03*
Y38582D03*
X1107100Y35582D03*
Y38582D03*
X1104461Y18126D03*
Y21126D03*
X1106961Y18126D03*
Y21126D03*
X1130031D03*
Y18126D03*
X1127531D03*
Y21126D03*
X1125031D03*
Y18126D03*
X1104601Y53737D03*
Y56737D03*
X1107101Y53737D03*
Y56737D03*
X1132670Y35582D03*
X1135170D03*
Y38582D03*
X1132670D03*
X1135031Y21126D03*
Y18126D03*
X1132531Y21126D03*
Y18126D03*
X1132950Y82867D03*
Y85867D03*
X1135450D03*
Y82867D03*
X1137950D03*
X1140450D03*
X1142950D03*
Y85867D03*
X1140450D03*
X1137950D03*
X1183321Y123652D03*
X1185821D03*
X1188321D03*
Y120652D03*
X1185821D03*
X1183321D03*
X1180821D03*
Y123652D03*
X1178321D03*
Y120652D03*
G54D21*
X140400Y258360D03*
X143400D03*
X140400Y261360D03*
X143400D03*
X140400Y255360D03*
X143400D03*
X165350Y220098D03*
X162850D03*
Y227185D03*
Y230728D03*
X165350Y223642D03*
Y227185D03*
Y230728D03*
X162850Y223642D03*
X157000Y414500D03*
X160500D03*
Y417500D03*
X157000D03*
X160500Y420500D03*
X157000D03*
X160500Y411500D03*
X157000D03*
X160500Y408500D03*
X157000D03*
X164000Y414600D03*
Y417600D03*
Y420600D03*
Y411600D03*
Y408600D03*
X160300Y423600D03*
X156800D03*
X160300Y426600D03*
X156800D03*
X163800Y426700D03*
Y423700D03*
X171939Y518000D03*
X168939D03*
X194160Y205200D03*
Y208200D03*
X200160Y205200D03*
Y208200D03*
X197160Y205200D03*
Y208200D03*
X208071Y305975D03*
X218500Y305000D03*
X226975D03*
X235975D03*
X239567Y305975D03*
X219939Y518000D03*
X216939D03*
X267939D03*
X264939D03*
X283000Y203500D03*
Y198500D03*
Y196000D03*
Y206000D03*
X285219Y279078D03*
X281219D03*
X277219D03*
X285219Y275078D03*
X281219D03*
X277219D03*
X285219Y271078D03*
X281219D03*
X277219D03*
Y283078D03*
X281219D03*
X285219D03*
X326000Y203500D03*
Y198500D03*
Y196000D03*
Y206000D03*
X304500Y203500D03*
Y198500D03*
Y196000D03*
Y206000D03*
X329419Y518000D03*
X326419D03*
X347500Y203500D03*
Y198500D03*
Y196000D03*
Y206000D03*
X390500Y203500D03*
Y198500D03*
Y196000D03*
Y206000D03*
X369000Y203500D03*
Y198500D03*
Y196000D03*
Y206000D03*
X375475Y305000D03*
X383975D03*
X365551Y305975D03*
X377419Y518000D03*
X374419D03*
X412000Y203500D03*
Y198500D03*
Y196000D03*
Y206000D03*
X393000Y305000D03*
X397047Y305975D03*
X442499Y279186D03*
X438499D03*
X434499D03*
X442499Y275186D03*
X438499D03*
X434499D03*
X442499Y271186D03*
X438499D03*
X434499D03*
Y283186D03*
X438499D03*
X442499D03*
X425419Y518000D03*
X422419D03*
X486900D03*
X483900D03*
X533475Y305500D03*
X523032Y305975D03*
X534900Y518000D03*
X531900D03*
X542475Y305500D03*
X551475D03*
X554528Y305975D03*
X562000Y442000D03*
X564500D03*
X590500Y203000D03*
Y198000D03*
Y195500D03*
Y205500D03*
X582900Y518000D03*
X579900D03*
X612000Y203000D03*
Y198000D03*
Y195500D03*
Y205500D03*
X647975Y37000D03*
X660200Y56800D03*
X655300D03*
X652300D03*
X655000Y203000D03*
Y198000D03*
Y195500D03*
Y205500D03*
X633500Y203000D03*
Y198000D03*
Y195500D03*
Y205500D03*
X644381Y518000D03*
X641381D03*
X684525Y32500D03*
Y36500D03*
X683600Y56800D03*
X679000D03*
X676000D03*
X686500D03*
X671100D03*
X668100D03*
X663200D03*
X676500Y195500D03*
Y198000D03*
Y203000D03*
Y205500D03*
X680513Y305975D03*
X699500Y34500D03*
X696900Y53300D03*
X694200D03*
X691400D03*
X689900Y56600D03*
X693000D03*
X696100Y56700D03*
X706000Y61975D03*
X697990Y195500D03*
Y198000D03*
Y203000D03*
Y205500D03*
X712009Y305975D03*
X708956Y305500D03*
X690956D03*
X700000D03*
X692381Y518000D03*
X689381D03*
X719490Y195500D03*
Y198000D03*
Y203000D03*
Y205500D03*
X732100Y332400D03*
X740381Y518000D03*
X737381D03*
X761560Y38500D03*
X758760D03*
X756160D03*
X761560Y30000D03*
X758760D03*
X756160D03*
X758900Y27400D03*
X761560Y55500D03*
X758760D03*
X756160D03*
X761560Y47000D03*
X758760D03*
X756160D03*
X761560Y64000D03*
X758760D03*
X756160D03*
X786500Y336484D03*
X819500Y329000D03*
X827500D03*
X813975Y357000D03*
X849490Y196000D03*
Y198500D03*
Y203500D03*
Y206000D03*
X846000Y260525D03*
X851000D03*
X856000D03*
X837575Y321000D03*
X844760Y336077D03*
X849000Y399000D03*
X865311Y486332D03*
X865257Y483503D03*
Y474684D03*
Y480503D03*
Y477684D03*
X854082Y505410D03*
X848263D03*
X851082D03*
X854082Y508410D03*
X848263D03*
X851082D03*
X854082Y511410D03*
X848263D03*
X851082D03*
X854082Y514410D03*
X848263D03*
X851082D03*
X845263Y508410D03*
X842434Y511464D03*
X845263Y511410D03*
X842434Y514464D03*
X845263Y514410D03*
X854082Y502410D03*
X848263D03*
X851082D03*
X842434Y502464D03*
X845263Y502410D03*
X842434Y505464D03*
X845263Y505410D03*
X842434Y508464D03*
Y523464D03*
X845263Y523410D03*
X854082Y517410D03*
X848263D03*
X851082D03*
Y520410D03*
X848263D03*
X854082D03*
X842434Y517464D03*
X845263Y517410D03*
Y520410D03*
X842434Y520464D03*
X854082Y523410D03*
X848263D03*
X851082D03*
X868311Y486332D03*
X868257Y483503D03*
Y477684D03*
Y480503D03*
Y474684D03*
X871311Y486332D03*
X874311D03*
X874257Y477684D03*
Y480503D03*
Y474684D03*
X871257Y483503D03*
Y474684D03*
Y480503D03*
Y477684D03*
X874257Y483503D03*
X1034500Y142000D03*
X1068900Y110000D03*
X1065000Y156425D03*
X1060000Y249000D03*
X1063000D03*
X1066000D03*
Y246000D03*
X1063000D03*
X1060000D03*
X1066000Y243000D03*
X1063000D03*
X1060000D03*
X1069000Y246000D03*
Y243000D03*
X1072000Y246000D03*
Y243000D03*
X1060000Y252000D03*
X1063000D03*
X1066000D03*
Y258000D03*
X1063000D03*
X1060000D03*
X1066000Y255000D03*
X1063000D03*
X1060000D03*
X1069000Y258000D03*
Y255000D03*
X1072000Y258000D03*
Y255000D03*
X1061600Y276242D03*
X1060000Y296500D03*
X1063000D03*
X1066000D03*
Y293500D03*
X1063000D03*
X1060000D03*
X1069000D03*
X1060000Y299500D03*
X1063000D03*
X1066000D03*
Y305500D03*
X1063000D03*
X1060000D03*
X1066000Y302500D03*
X1063000D03*
X1060000D03*
X1069000Y305500D03*
Y302500D03*
X1066000Y290500D03*
X1063000D03*
X1060000D03*
X1069000D03*
X1072000Y293500D03*
Y305500D03*
Y302500D03*
Y290500D03*
X1066000Y338000D03*
X1063000D03*
X1060000D03*
X1069000D03*
X1072000D03*
X1061600Y323742D03*
X1060000Y344000D03*
X1063000D03*
X1066000D03*
X1060000Y347000D03*
X1063000D03*
X1066000D03*
Y341000D03*
X1063000D03*
X1060000D03*
X1066000Y353000D03*
X1063000D03*
X1060000D03*
X1066000Y350000D03*
X1063000D03*
X1060000D03*
X1069000Y353000D03*
Y350000D03*
Y341000D03*
X1072000Y353000D03*
Y350000D03*
Y341000D03*
X1061600Y359642D03*
X1066000Y397500D03*
X1063000D03*
X1060000D03*
X1069000D03*
X1060000Y391500D03*
X1063000D03*
X1066000D03*
X1060000Y394500D03*
X1063000D03*
X1066000D03*
Y388500D03*
X1063000D03*
X1060000D03*
X1066000Y385500D03*
X1063000D03*
X1060000D03*
X1069000Y388500D03*
Y385500D03*
X1072000Y397500D03*
Y388500D03*
Y385500D03*
X1066000Y400500D03*
X1063000D03*
X1060000D03*
X1069000D03*
X1072000D03*
X1060984Y418742D03*
X1066000Y433000D03*
X1063000D03*
X1060000D03*
X1069000D03*
X1060000Y439000D03*
X1063000D03*
X1066000D03*
X1060000Y442000D03*
X1063000D03*
X1066000D03*
Y436000D03*
X1063000D03*
X1060000D03*
X1069000D03*
X1072000Y433000D03*
Y436000D03*
X1066000Y448000D03*
X1063000D03*
X1060000D03*
X1066000Y445000D03*
X1063000D03*
X1060000D03*
X1069000Y448000D03*
Y445000D03*
X1072000Y448000D03*
Y445000D03*
X1069000Y480500D03*
Y483500D03*
X1060000Y480500D03*
X1063000D03*
X1066000D03*
X1060000Y483500D03*
X1063000D03*
X1066000D03*
Y486500D03*
X1063000D03*
X1060000D03*
X1072000Y480500D03*
Y483500D03*
X1061600Y466242D03*
X1069000Y492500D03*
Y495500D03*
X1060000Y492500D03*
X1063000D03*
X1066000D03*
X1060000Y495500D03*
X1063000D03*
X1066000D03*
Y489500D03*
X1063000D03*
X1060000D03*
X1072000Y492500D03*
Y495500D03*
X1061600Y513742D03*
X1091000Y99500D03*
X1095100D03*
X1073200Y126000D03*
Y128800D03*
Y123200D03*
X1084740Y108000D03*
X1100075Y139925D03*
X1084260Y152600D03*
X1101903Y285019D03*
X1101796Y331894D03*
X1074316Y406925D03*
X1113000Y101240D03*
X1119500Y86000D03*
Y83000D03*
X1123000Y120816D03*
X1126000D03*
X1131500D03*
X1113500Y147500D03*
X1118774Y284699D03*
X1112902D03*
X1110019Y284806D03*
X1104786Y284912D03*
X1121657Y284592D03*
X1118667Y331574D03*
X1112795D03*
X1109912Y331681D03*
X1104679Y331787D03*
X1121550Y331467D03*
X1104009Y427245D03*
X1120880Y426925D03*
X1115008D03*
X1112125Y427032D03*
X1106892Y427138D03*
X1123763Y426818D03*
X1103800Y474339D03*
X1106683Y474232D03*
X1111916Y474126D03*
X1114799Y474019D03*
X1120671D03*
X1123554Y473912D03*
X1155000Y124913D03*
X1159300Y129700D03*
X1134500Y120816D03*
X1154000Y151500D03*
X1160200Y175982D03*
X1152500Y186500D03*
X1138203Y266860D03*
Y260860D03*
Y263860D03*
X1135203Y260860D03*
Y263860D03*
Y266860D03*
X1138203Y257860D03*
Y254860D03*
X1135203Y257860D03*
Y254860D03*
X1135403Y302360D03*
Y305360D03*
X1138403Y302360D03*
Y305360D03*
X1135403Y308360D03*
X1138403D03*
X1135403Y314360D03*
Y311360D03*
X1138403D03*
Y314360D03*
Y361979D03*
X1135403D03*
X1138403Y358979D03*
X1135403D03*
X1138403Y355979D03*
X1135403D03*
X1138403Y352979D03*
X1135403D03*
X1138403Y349979D03*
X1135403D03*
X1135190Y396965D03*
X1138190D03*
X1135190Y399965D03*
X1138190D03*
X1135190Y402965D03*
Y405965D03*
Y408965D03*
X1138190Y402965D03*
Y405965D03*
Y408965D03*
X1135404Y457228D03*
Y454228D03*
Y451228D03*
Y445228D03*
Y448228D03*
X1138404Y454228D03*
Y451228D03*
Y445228D03*
Y448228D03*
Y457228D03*
X1135622Y485732D03*
Y470732D03*
Y467732D03*
Y479732D03*
Y476732D03*
Y473732D03*
Y482732D03*
X1138622D03*
Y473732D03*
Y476732D03*
Y479732D03*
Y470732D03*
Y485732D03*
Y467732D03*
X1177475Y111500D03*
X1179500Y105500D03*
X1162700Y175959D03*
X1203887Y306894D03*
X1200887D03*
X1197887D03*
X1203887Y303894D03*
X1200887D03*
X1197887D03*
X1203887Y300894D03*
X1200887D03*
X1197887D03*
X1203887Y297894D03*
X1200887D03*
X1197887D03*
X1203887Y294894D03*
X1200887D03*
X1197887D03*
Y321894D03*
X1200887D03*
X1203887D03*
Y318894D03*
X1200887D03*
X1197887D03*
X1203887Y315894D03*
X1200887D03*
X1197887D03*
X1203887Y312894D03*
X1200887D03*
X1197887D03*
X1203887Y309894D03*
X1200887D03*
X1197887D03*
X1197976Y437394D03*
X1200976D03*
X1203976D03*
X1197976Y440394D03*
X1200976D03*
X1203976D03*
X1197976Y443394D03*
X1200976D03*
X1203976D03*
X1197976Y446394D03*
X1200976D03*
X1203976D03*
X1197976Y449394D03*
X1200976D03*
X1203976D03*
X1197976Y452394D03*
X1200976D03*
X1203976D03*
X1197976Y455394D03*
X1200976D03*
X1203976D03*
X1197976Y464394D03*
X1200976D03*
X1203976D03*
X1197976Y458394D03*
X1200976D03*
X1203976D03*
X1197976Y461394D03*
X1200976D03*
X1203976D03*
G54D36*
X712559Y129408D03*
Y119408D03*
Y149408D03*
Y139408D03*
X722559Y129408D03*
Y119408D03*
X747559Y129408D03*
Y119408D03*
X722559Y149408D03*
Y139408D03*
X747559Y149408D03*
Y139408D03*
X757559Y129408D03*
Y119408D03*
Y149408D03*
Y139408D03*
X782559Y129408D03*
Y119408D03*
X792559Y129408D03*
Y119408D03*
X782559Y149408D03*
Y139408D03*
X792559Y149408D03*
Y139408D03*
X812559D03*
X852559Y129408D03*
Y119408D03*
X862559Y129408D03*
Y119408D03*
X852559Y149408D03*
Y139408D03*
X862559Y149408D03*
Y139408D03*
X887559Y129408D03*
Y119408D03*
Y149408D03*
Y139408D03*
X897559Y129408D03*
Y119408D03*
X922559Y129408D03*
Y119408D03*
X897559Y149408D03*
Y139408D03*
X922559Y149408D03*
Y139408D03*
X932559Y129408D03*
Y119408D03*
Y149408D03*
Y139408D03*
G54D46*
X1226024Y174429D03*
Y399429D03*
G54D17*
X33780Y324724D03*
G54D32*
X268000Y240000D03*
X312500D03*
X357000D03*
X428500D03*
X472500D03*
X516500D03*
X578500D03*
X622500D03*
X666500D03*
X735981D03*
X779981D03*
X823981D03*
G54D15*
X38780Y232598D03*
Y239291D03*
Y252598D03*
Y259291D03*
Y272598D03*
Y279291D03*
Y292598D03*
Y299291D03*
X48780Y232598D03*
Y239291D03*
Y252598D03*
Y259291D03*
Y272598D03*
Y279291D03*
Y292598D03*
Y299291D03*
G54D45*
X1240158Y57480D03*
Y521260D03*
G54D33*
X253819Y477204D03*
X411299D03*
X568780D03*
X726261D03*
G54D37*
X753314Y607542D03*
G54D39*
X753420Y635687D03*
%LPC*%
G75*
G54D47*
G01X-297025Y-1013390D02*
Y1828909D01*
X3691357D01*
Y-1013390D01*
X-297025D01*
G01X4093Y-769672D02*
Y-844672D01*
X504093D01*
Y-769672D01*
X4093D01*
G01X16093Y-834672D02*
Y-839672D01*
G01X14636Y-834672D02*
X17550D01*
G01X22460Y-839672D02*
X19926D01*
Y-834672D01*
X22460D01*
G01X21446Y-837089D02*
X19926D01*
G01X25026Y-834672D02*
Y-839672D01*
X27560D01*
G01X31393Y-839839D02*
X31266Y-839755D01*
Y-839589D01*
X31393Y-839505D01*
X31520Y-839589D01*
Y-839755D01*
X31393Y-839839D01*
G01Y-837589D02*
X31266Y-837505D01*
Y-837339D01*
X31393Y-837255D01*
X31520Y-837339D01*
Y-837505D01*
X31393Y-837589D01*
G01X36176Y-841339D02*
X35543Y-840505D01*
X35226Y-839672D01*
Y-836339D01*
X35543Y-835505D01*
X36176Y-834672D01*
G01X41593D02*
X41086Y-834839D01*
X40706Y-835255D01*
X40453Y-835755D01*
X40263Y-836422D01*
X40200Y-837172D01*
X40263Y-837922D01*
X40453Y-838589D01*
X40706Y-839089D01*
X41086Y-839505D01*
X41593Y-839672D01*
X42100Y-839505D01*
X42480Y-839089D01*
X42733Y-838589D01*
X42923Y-837922D01*
X42986Y-837172D01*
X42923Y-836422D01*
X42733Y-835755D01*
X42480Y-835255D01*
X42100Y-834839D01*
X41593Y-834672D01*
G01X45300Y-838672D02*
X45680Y-839255D01*
X46186Y-839589D01*
X46756Y-839672D01*
X47263Y-839589D01*
X47770Y-839172D01*
X48086Y-838672D01*
X48150Y-838172D01*
X48023Y-837589D01*
X47580Y-837172D01*
X47136Y-837005D01*
X46566D01*
G01X47136D02*
X47516Y-836755D01*
X47833Y-836339D01*
X47960Y-835839D01*
X47833Y-835339D01*
X47516Y-834922D01*
X46946Y-834672D01*
X46376Y-834755D01*
X45806Y-835089D01*
G01X52110Y-841339D02*
X52743Y-840505D01*
X53060Y-839672D01*
Y-836339D01*
X52743Y-835505D01*
X52110Y-834672D01*
G01X55500Y-838672D02*
X55880Y-839255D01*
X56386Y-839589D01*
X56956Y-839672D01*
X57463Y-839589D01*
X57970Y-839172D01*
X58286Y-838672D01*
X58350Y-838172D01*
X58223Y-837589D01*
X57780Y-837172D01*
X57336Y-837005D01*
X56766D01*
G01X57336D02*
X57716Y-836755D01*
X58033Y-836339D01*
X58160Y-835839D01*
X58033Y-835339D01*
X57716Y-834922D01*
X57146Y-834672D01*
X56576Y-834755D01*
X56006Y-835089D01*
G01X60790Y-835505D02*
X61170Y-835005D01*
X61613Y-834755D01*
X62120Y-834672D01*
X62753Y-834839D01*
X63196Y-835255D01*
X63323Y-835755D01*
X63260Y-836255D01*
X63006Y-836672D01*
X61740Y-837505D01*
X61170Y-838089D01*
X60790Y-838922D01*
X60663Y-839672D01*
X63323D01*
G01X66966D02*
X67093Y-838589D01*
X67283Y-837672D01*
X67536Y-836839D01*
X67853Y-835922D01*
X68360Y-834672D01*
X65826D01*
G01X71370Y-838005D02*
X73016D01*
G01X76090Y-835505D02*
X76470Y-835005D01*
X76913Y-834755D01*
X77420Y-834672D01*
X78053Y-834839D01*
X78496Y-835255D01*
X78623Y-835755D01*
X78560Y-836255D01*
X78306Y-836672D01*
X77040Y-837505D01*
X76470Y-838089D01*
X76090Y-838922D01*
X75963Y-839672D01*
X78623D01*
G01X81000Y-838672D02*
X81380Y-839255D01*
X81886Y-839589D01*
X82456Y-839672D01*
X82963Y-839589D01*
X83470Y-839172D01*
X83786Y-838672D01*
X83850Y-838172D01*
X83723Y-837589D01*
X83280Y-837172D01*
X82836Y-837005D01*
X82266D01*
G01X82836D02*
X83216Y-836755D01*
X83533Y-836339D01*
X83660Y-835839D01*
X83533Y-835339D01*
X83216Y-834922D01*
X82646Y-834672D01*
X82076Y-834755D01*
X81506Y-835089D01*
G01X88253Y-839672D02*
Y-834672D01*
X85910Y-838255D01*
X89076D01*
G01X91200Y-838922D02*
X91580Y-839339D01*
X92023Y-839589D01*
X92593Y-839672D01*
X93163Y-839505D01*
X93606Y-839172D01*
X93923Y-838589D01*
X93986Y-837922D01*
X93860Y-837255D01*
X93543Y-836839D01*
X93100Y-836505D01*
X92656Y-836422D01*
X92213Y-836505D01*
X91643Y-836839D01*
X91833Y-834672D01*
X93543D01*
G01X101590Y-839672D02*
Y-834672D01*
X103996D01*
G01X103110Y-837089D02*
X101590D01*
G01X106310Y-839672D02*
X107893Y-834672D01*
X109476Y-839672D01*
G01X108906Y-837922D02*
X106880D01*
G01X111663Y-839672D02*
X114323Y-834672D01*
G01X111663D02*
X114323Y-839672D01*
G01X118093Y-839839D02*
X117966Y-839755D01*
Y-839589D01*
X118093Y-839505D01*
X118220Y-839589D01*
Y-839755D01*
X118093Y-839839D01*
G01Y-837589D02*
X117966Y-837505D01*
Y-837339D01*
X118093Y-837255D01*
X118220Y-837339D01*
Y-837505D01*
X118093Y-837589D01*
G01X122876Y-841339D02*
X122243Y-840505D01*
X121926Y-839672D01*
Y-836339D01*
X122243Y-835505D01*
X122876Y-834672D01*
G01X128293D02*
X127786Y-834839D01*
X127406Y-835255D01*
X127153Y-835755D01*
X126963Y-836422D01*
X126900Y-837172D01*
X126963Y-837922D01*
X127153Y-838589D01*
X127406Y-839089D01*
X127786Y-839505D01*
X128293Y-839672D01*
X128800Y-839505D01*
X129180Y-839089D01*
X129433Y-838589D01*
X129623Y-837922D01*
X129686Y-837172D01*
X129623Y-836422D01*
X129433Y-835755D01*
X129180Y-835255D01*
X128800Y-834839D01*
X128293Y-834672D01*
G01X132000Y-838672D02*
X132380Y-839255D01*
X132886Y-839589D01*
X133456Y-839672D01*
X133963Y-839589D01*
X134470Y-839172D01*
X134786Y-838672D01*
X134850Y-838172D01*
X134723Y-837589D01*
X134280Y-837172D01*
X133836Y-837005D01*
X133266D01*
G01X133836D02*
X134216Y-836755D01*
X134533Y-836339D01*
X134660Y-835839D01*
X134533Y-835339D01*
X134216Y-834922D01*
X133646Y-834672D01*
X133076Y-834755D01*
X132506Y-835089D01*
G01X138810Y-841339D02*
X139443Y-840505D01*
X139760Y-839672D01*
Y-836339D01*
X139443Y-835505D01*
X138810Y-834672D01*
G01X142200Y-838672D02*
X142580Y-839255D01*
X143086Y-839589D01*
X143656Y-839672D01*
X144163Y-839589D01*
X144670Y-839172D01*
X144986Y-838672D01*
X145050Y-838172D01*
X144923Y-837589D01*
X144480Y-837172D01*
X144036Y-837005D01*
X143466D01*
G01X144036D02*
X144416Y-836755D01*
X144733Y-836339D01*
X144860Y-835839D01*
X144733Y-835339D01*
X144416Y-834922D01*
X143846Y-834672D01*
X143276Y-834755D01*
X142706Y-835089D01*
G01X147616Y-839089D02*
X148060Y-839505D01*
X148566Y-839672D01*
X149073Y-839505D01*
X149516Y-839005D01*
X149833Y-838255D01*
X149960Y-837505D01*
Y-836589D01*
X149833Y-835839D01*
X149516Y-835172D01*
X149136Y-834839D01*
X148693Y-834672D01*
X148186Y-834839D01*
X147806Y-835172D01*
X147553Y-835672D01*
X147426Y-836339D01*
X147553Y-836922D01*
X147870Y-837505D01*
X148250Y-837839D01*
X148693Y-837922D01*
X149200Y-837755D01*
X149580Y-837339D01*
X149960Y-836589D01*
G01X153666Y-839672D02*
X153793Y-838589D01*
X153983Y-837672D01*
X154236Y-836839D01*
X154553Y-835922D01*
X155060Y-834672D01*
X152526D01*
G01X158070Y-838005D02*
X159716D01*
G01X162600Y-838672D02*
X162980Y-839255D01*
X163486Y-839589D01*
X164056Y-839672D01*
X164563Y-839589D01*
X165070Y-839172D01*
X165386Y-838672D01*
X165450Y-838172D01*
X165323Y-837589D01*
X164880Y-837172D01*
X164436Y-837005D01*
X163866D01*
G01X164436D02*
X164816Y-836755D01*
X165133Y-836339D01*
X165260Y-835839D01*
X165133Y-835339D01*
X164816Y-834922D01*
X164246Y-834672D01*
X163676Y-834755D01*
X163106Y-835089D01*
G01X167890Y-837589D02*
X168333Y-837005D01*
X168713Y-836672D01*
X169220Y-836505D01*
X169663Y-836672D01*
X169980Y-837005D01*
X170233Y-837505D01*
X170296Y-838089D01*
X170233Y-838589D01*
X169980Y-839089D01*
X169600Y-839505D01*
X169156Y-839672D01*
X168650Y-839505D01*
X168206Y-839005D01*
X167953Y-838255D01*
X167890Y-837422D01*
X168016Y-836339D01*
X168206Y-835755D01*
X168523Y-835172D01*
X168966Y-834755D01*
X169410Y-834672D01*
X169853Y-834839D01*
X170170Y-835255D01*
G01X174193Y-839672D02*
Y-834672D01*
X173433Y-835672D01*
G01Y-839672D02*
X174953D01*
G01X180053D02*
Y-834672D01*
X177710Y-838255D01*
X180876D01*
G01X199093Y-769672D02*
Y-844672D01*
G01Y-819672D02*
X302093D01*
Y-794672D01*
G01X199093D02*
X302093D01*
G01X309600Y-829672D02*
Y-824672D01*
X310866D01*
X311373Y-824922D01*
X311753Y-825255D01*
X312070Y-825755D01*
X312323Y-826339D01*
X312386Y-827172D01*
X312323Y-828005D01*
X312070Y-828589D01*
X311753Y-829089D01*
X311373Y-829422D01*
X310866Y-829672D01*
X309600D01*
G01X314510D02*
X316093Y-824672D01*
X317676Y-829672D01*
G01X317106Y-827922D02*
X315080D01*
G01X321193Y-824672D02*
Y-829672D01*
G01X319736Y-824672D02*
X322650D01*
G01X327560Y-829672D02*
X325026D01*
Y-824672D01*
X327560D01*
G01X326546Y-827089D02*
X325026D01*
G01X331393Y-829839D02*
X331266Y-829755D01*
Y-829589D01*
X331393Y-829505D01*
X331520Y-829589D01*
Y-829755D01*
X331393Y-829839D01*
G01Y-827589D02*
X331266Y-827505D01*
Y-827339D01*
X331393Y-827255D01*
X331520Y-827339D01*
Y-827505D01*
X331393Y-827589D01*
G01X304093Y-769672D02*
Y-844672D01*
G01X302093Y-769672D02*
Y-844672D01*
G01X304093Y-819672D02*
X504093D01*
G01X309726Y-804672D02*
Y-799672D01*
X311246D01*
X311753Y-799922D01*
X312133Y-800505D01*
X312260Y-801172D01*
X312133Y-801839D01*
X311816Y-802339D01*
X311246Y-802589D01*
X309726D01*
G01X314953Y-804839D02*
X317233Y-799672D01*
G01X319736Y-804672D02*
Y-799672D01*
X322650Y-804672D01*
Y-799672D01*
G01X326293Y-804839D02*
X326166Y-804755D01*
Y-804589D01*
X326293Y-804505D01*
X326420Y-804589D01*
Y-804755D01*
X326293Y-804839D01*
G01Y-802589D02*
X326166Y-802505D01*
Y-802339D01*
X326293Y-802255D01*
X326420Y-802339D01*
Y-802505D01*
X326293Y-802589D01*
G01X304093Y-794672D02*
X504093D01*
G01X309726Y-779672D02*
Y-774672D01*
X311246D01*
X311753Y-774922D01*
X312133Y-775505D01*
X312260Y-776172D01*
X312133Y-776839D01*
X311816Y-777339D01*
X311246Y-777589D01*
X309726D01*
G01X314826Y-779672D02*
Y-774672D01*
X316410D01*
X316916Y-774922D01*
X317233Y-775255D01*
X317360Y-775922D01*
X317233Y-776589D01*
X316853Y-777005D01*
X316410Y-777255D01*
X314826D01*
G01X316410D02*
X317360Y-779672D01*
G01X321193D02*
X320686Y-779589D01*
X320243Y-779255D01*
X319863Y-778755D01*
X319610Y-778172D01*
X319483Y-777505D01*
Y-776839D01*
X319610Y-776172D01*
X319863Y-775589D01*
X320243Y-775089D01*
X320686Y-774755D01*
X321193Y-774672D01*
X321700Y-774755D01*
X322143Y-775089D01*
X322523Y-775589D01*
X322776Y-776172D01*
X322903Y-776839D01*
Y-777505D01*
X322776Y-778172D01*
X322523Y-778755D01*
X322143Y-779255D01*
X321700Y-779589D01*
X321193Y-779672D01*
G01X325026Y-778672D02*
X325343Y-779172D01*
X325723Y-779505D01*
X326166Y-779672D01*
X326673Y-779505D01*
X327053Y-779172D01*
X327433Y-778672D01*
X327560Y-778005D01*
Y-774672D01*
G01X332660Y-779672D02*
X330126D01*
Y-774672D01*
X332660D01*
G01X331646Y-777089D02*
X330126D01*
G01X337886Y-775089D02*
X337506Y-774839D01*
X337063Y-774672D01*
X336556D01*
X335986Y-774922D01*
X335543Y-775339D01*
X335226Y-775839D01*
X334973Y-776672D01*
X334910Y-777422D01*
X335036Y-778172D01*
X335226Y-778672D01*
X335606Y-779172D01*
X336050Y-779505D01*
X336493Y-779672D01*
X336936D01*
X337380Y-779505D01*
X337760Y-779255D01*
X338076Y-778922D01*
G01X341593Y-774672D02*
Y-779672D01*
G01X340136Y-774672D02*
X343050D01*
G01X346693Y-779839D02*
X346566Y-779755D01*
Y-779589D01*
X346693Y-779505D01*
X346820Y-779589D01*
Y-779755D01*
X346693Y-779839D01*
G01Y-777589D02*
X346566Y-777505D01*
Y-777339D01*
X346693Y-777255D01*
X346820Y-777339D01*
Y-777505D01*
X346693Y-777589D01*
G01X419093Y-819672D02*
Y-844672D01*
G01X421726Y-822172D02*
Y-827172D01*
X424260D01*
G01X427333Y-822172D02*
X428853D01*
G01X428093D02*
Y-827172D01*
G01X427333D02*
X428853D01*
G01X433700Y-824505D02*
X433953Y-824255D01*
X434143Y-823839D01*
X434270Y-823255D01*
X434143Y-822755D01*
X433890Y-822422D01*
X433446Y-822172D01*
X431736D01*
Y-827172D01*
X433826D01*
X434270Y-826839D01*
X434523Y-826339D01*
X434650Y-825755D01*
X434523Y-825172D01*
X434143Y-824672D01*
X433700Y-824505D01*
X431736D01*
G01X438293Y-827339D02*
X438166Y-827255D01*
Y-827089D01*
X438293Y-827005D01*
X438420Y-827089D01*
Y-827255D01*
X438293Y-827339D01*
G01Y-825089D02*
X438166Y-825005D01*
Y-824839D01*
X438293Y-824755D01*
X438420Y-824839D01*
Y-825005D01*
X438293Y-825089D01*
G01X470106Y-847839D02*
X470213Y-847714D01*
X470293Y-847505D01*
X470346Y-847214D01*
X470293Y-846964D01*
X470186Y-846797D01*
X470000Y-846672D01*
X469280D01*
Y-849172D01*
X470160D01*
X470346Y-849005D01*
X470453Y-848755D01*
X470506Y-848464D01*
X470453Y-848172D01*
X470293Y-847922D01*
X470106Y-847839D01*
X469280D01*
G01X472573Y-849172D02*
Y-847505D01*
G01Y-847797D02*
X472466Y-847630D01*
X472306Y-847547D01*
X472120Y-847505D01*
X471933Y-847589D01*
X471773Y-847755D01*
X471666Y-848005D01*
X471613Y-848339D01*
X471666Y-848672D01*
X471773Y-848922D01*
X471933Y-849089D01*
X472120Y-849172D01*
X472306Y-849130D01*
X472466Y-849005D01*
X472573Y-848839D01*
G01X473893Y-848880D02*
X474026Y-849047D01*
X474213Y-849172D01*
X474373D01*
X474533Y-849089D01*
X474640Y-848964D01*
X474693Y-848797D01*
X474666Y-848547D01*
X474560Y-848422D01*
X474080Y-848172D01*
X473973Y-847880D01*
X474026Y-847672D01*
X474133Y-847547D01*
X474293Y-847505D01*
X474453Y-847547D01*
X474613Y-847672D01*
G01X476093Y-848047D02*
X476946D01*
X476866Y-847755D01*
X476733Y-847589D01*
X476546Y-847505D01*
X476360Y-847547D01*
X476200Y-847672D01*
X476093Y-847964D01*
X476040Y-848214D01*
Y-848464D01*
X476093Y-848714D01*
X476226Y-848964D01*
X476386Y-849130D01*
X476573Y-849172D01*
X476760Y-849089D01*
X476946Y-848839D01*
G01X478213Y-849172D02*
Y-846672D01*
G01Y-847922D02*
X478346Y-847672D01*
X478506Y-847547D01*
X478666Y-847505D01*
X478906Y-847589D01*
X479066Y-847755D01*
X479173Y-848047D01*
Y-848380D01*
X479120Y-848714D01*
X479013Y-848964D01*
X478826Y-849130D01*
X478666Y-849172D01*
X478506Y-849130D01*
X478346Y-849005D01*
X478213Y-848797D01*
G01X480893Y-849172D02*
X480733Y-849130D01*
X480573Y-848964D01*
X480466Y-848672D01*
X480413Y-848339D01*
X480466Y-848005D01*
X480573Y-847714D01*
X480733Y-847547D01*
X480893Y-847505D01*
X481053Y-847547D01*
X481213Y-847714D01*
X481320Y-848005D01*
X481346Y-848339D01*
X481320Y-848672D01*
X481213Y-848964D01*
X481053Y-849130D01*
X480893Y-849172D01*
G01X483573D02*
Y-847505D01*
G01Y-847797D02*
X483466Y-847630D01*
X483306Y-847547D01*
X483120Y-847505D01*
X482933Y-847589D01*
X482773Y-847755D01*
X482666Y-848005D01*
X482613Y-848339D01*
X482666Y-848672D01*
X482773Y-848922D01*
X482933Y-849089D01*
X483120Y-849172D01*
X483306Y-849130D01*
X483466Y-849005D01*
X483573Y-848839D01*
G01X484920Y-849172D02*
Y-847505D01*
G01Y-847839D02*
X485053Y-847672D01*
X485186Y-847547D01*
X485373Y-847505D01*
X485506Y-847547D01*
X485666Y-847672D01*
G01X487973Y-846672D02*
Y-849172D01*
G01Y-848797D02*
X487866Y-849005D01*
X487706Y-849130D01*
X487520Y-849172D01*
X487306Y-849089D01*
X487146Y-848880D01*
X487040Y-848630D01*
X487013Y-848339D01*
X487040Y-848047D01*
X487146Y-847797D01*
X487306Y-847589D01*
X487520Y-847505D01*
X487706Y-847547D01*
X487840Y-847630D01*
X487973Y-847797D01*
G01X491360Y-849172D02*
Y-846672D01*
X492026D01*
X492240Y-846797D01*
X492373Y-846964D01*
X492426Y-847297D01*
X492373Y-847630D01*
X492213Y-847839D01*
X492026Y-847964D01*
X491360D01*
G01X492026D02*
X492426Y-849172D01*
G01X493693Y-848047D02*
X494546D01*
X494466Y-847755D01*
X494333Y-847589D01*
X494146Y-847505D01*
X493960Y-847547D01*
X493800Y-847672D01*
X493693Y-847964D01*
X493640Y-848214D01*
Y-848464D01*
X493693Y-848714D01*
X493826Y-848964D01*
X493986Y-849130D01*
X494173Y-849172D01*
X494360Y-849089D01*
X494546Y-848839D01*
G01X495813Y-847505D02*
X496293Y-849172D01*
X496773Y-847505D01*
G01X498493Y-849255D02*
X498440Y-849214D01*
Y-849130D01*
X498493Y-849089D01*
X498546Y-849130D01*
Y-849214D01*
X498493Y-849255D01*
G01X500693Y-849172D02*
X500880Y-849130D01*
X501093Y-849005D01*
X501226Y-848797D01*
X501280Y-848505D01*
X501226Y-848214D01*
X501066Y-847964D01*
X500826Y-847839D01*
X500560D01*
X500400Y-847755D01*
X500266Y-847547D01*
X500213Y-847255D01*
X500293Y-846964D01*
X500480Y-846755D01*
X500693Y-846672D01*
X500906Y-846755D01*
X501093Y-846964D01*
X501173Y-847255D01*
X501120Y-847547D01*
X500986Y-847755D01*
X500826Y-847839D01*
X500560D01*
X500320Y-847964D01*
X500160Y-848214D01*
X500106Y-848505D01*
X500160Y-848797D01*
X500293Y-849005D01*
X500506Y-849130D01*
X500693Y-849172D01*
G01X503106Y-847839D02*
X503213Y-847714D01*
X503293Y-847505D01*
X503346Y-847214D01*
X503293Y-846964D01*
X503186Y-846797D01*
X503000Y-846672D01*
X502280D01*
Y-849172D01*
X503160D01*
X503346Y-849005D01*
X503453Y-848755D01*
X503506Y-848464D01*
X503453Y-848172D01*
X503293Y-847922D01*
X503106Y-847839D01*
X502280D01*
G01X465993Y-822172D02*
Y-827172D01*
G01X464536Y-822172D02*
X467450D01*
G01X471093Y-827172D02*
X470713Y-827089D01*
X470333Y-826755D01*
X470080Y-826172D01*
X469953Y-825505D01*
X470080Y-824839D01*
X470333Y-824255D01*
X470713Y-823922D01*
X471093Y-823839D01*
X471473Y-823922D01*
X471853Y-824255D01*
X472106Y-824839D01*
X472170Y-825505D01*
X472106Y-826172D01*
X471853Y-826755D01*
X471473Y-827089D01*
X471093Y-827172D01*
G01X476193D02*
X475813Y-827089D01*
X475433Y-826755D01*
X475180Y-826172D01*
X475053Y-825505D01*
X475180Y-824839D01*
X475433Y-824255D01*
X475813Y-823922D01*
X476193Y-823839D01*
X476573Y-823922D01*
X476953Y-824255D01*
X477206Y-824839D01*
X477270Y-825505D01*
X477206Y-826172D01*
X476953Y-826755D01*
X476573Y-827089D01*
X476193Y-827172D01*
G01X481293D02*
Y-822172D01*
G01X486393Y-827339D02*
X486266Y-827255D01*
Y-827089D01*
X486393Y-827005D01*
X486520Y-827089D01*
Y-827255D01*
X486393Y-827339D01*
G01Y-825089D02*
X486266Y-825005D01*
Y-824839D01*
X486393Y-824755D01*
X486520Y-824839D01*
Y-825005D01*
X486393Y-825089D01*
G01X462093Y-819672D02*
Y-844672D01*
G01Y-794672D02*
Y-819672D01*
G01X464726Y-802172D02*
Y-797172D01*
X466310D01*
X466816Y-797422D01*
X467133Y-797755D01*
X467260Y-798422D01*
X467133Y-799089D01*
X466753Y-799505D01*
X466310Y-799755D01*
X464726D01*
G01X466310D02*
X467260Y-802172D01*
G01X472360D02*
X469826D01*
Y-797172D01*
X472360D01*
G01X471346Y-799589D02*
X469826D01*
G01X474610Y-797172D02*
X476193Y-802172D01*
X477776Y-797172D01*
G01X481293Y-802339D02*
X481166Y-802255D01*
Y-802089D01*
X481293Y-802005D01*
X481420Y-802089D01*
Y-802255D01*
X481293Y-802339D01*
G01Y-800089D02*
X481166Y-800005D01*
Y-799839D01*
X481293Y-799755D01*
X481420Y-799839D01*
Y-800005D01*
X481293Y-800089D01*
G01X-297025Y-1013390D02*
Y1828909D01*
X3691357D01*
Y-1013390D01*
X-297025D01*
G01X16913Y-817022D02*
X18480D01*
Y-818912D01*
X18010Y-819542D01*
X17461Y-819962D01*
X16678Y-820172D01*
X15895Y-819962D01*
X15346Y-819542D01*
X14876Y-818912D01*
X14563Y-818177D01*
X14406Y-817337D01*
Y-816602D01*
X14563Y-815972D01*
X14876Y-815237D01*
X15346Y-814607D01*
X15816Y-814187D01*
X16443Y-813872D01*
X16991D01*
X17618Y-814082D01*
X18088Y-814502D01*
G01X21020Y-813872D02*
Y-818387D01*
X21333Y-819332D01*
X21960Y-819962D01*
X22743Y-820172D01*
X23526Y-819962D01*
X24153Y-819332D01*
X24466Y-818387D01*
Y-813872D01*
G01X28103D02*
X29983D01*
G01X29043D02*
Y-820172D01*
G01X28103D02*
X29983D01*
G01X33698Y-819332D02*
X34325Y-819857D01*
X35030Y-820172D01*
X35656D01*
X36283Y-819857D01*
X36753Y-819332D01*
X36988Y-818597D01*
X36831Y-817862D01*
X36440Y-817232D01*
X35735Y-816812D01*
X34795Y-816602D01*
X34246Y-816182D01*
X34011Y-815447D01*
X34168Y-814712D01*
X34560Y-814187D01*
X35108Y-813872D01*
X35656D01*
X36205Y-814082D01*
X36675Y-814607D01*
G01X39998Y-820172D02*
Y-813872D01*
G01X43288D02*
Y-820172D01*
G01Y-817022D02*
X39998D01*
G01X45985Y-820172D02*
X47943Y-813872D01*
X49901Y-820172D01*
G01X49196Y-817967D02*
X46690D01*
G01X52441Y-820172D02*
Y-813872D01*
X56045Y-820172D01*
Y-813872D01*
G01X65120Y-820172D02*
Y-813872D01*
X66686D01*
X67313Y-814187D01*
X67783Y-814607D01*
X68175Y-815237D01*
X68488Y-815972D01*
X68566Y-817022D01*
X68488Y-818072D01*
X68175Y-818807D01*
X67783Y-819437D01*
X67313Y-819857D01*
X66686Y-820172D01*
X65120D01*
G01X72203Y-813872D02*
X74083D01*
G01X73143D02*
Y-820172D01*
G01X72203D02*
X74083D01*
G01X77798Y-819332D02*
X78425Y-819857D01*
X79130Y-820172D01*
X79756D01*
X80383Y-819857D01*
X80853Y-819332D01*
X81088Y-818597D01*
X80931Y-817862D01*
X80540Y-817232D01*
X79835Y-816812D01*
X78895Y-816602D01*
X78346Y-816182D01*
X78111Y-815447D01*
X78268Y-814712D01*
X78660Y-814187D01*
X79208Y-813872D01*
X79756D01*
X80305Y-814082D01*
X80775Y-814607D01*
G01X85743Y-813872D02*
Y-820172D01*
G01X83941Y-813872D02*
X87545D01*
G01X92043Y-820382D02*
X91886Y-820277D01*
Y-820067D01*
X92043Y-819962D01*
X92200Y-820067D01*
Y-820277D01*
X92043Y-820382D01*
G01X98186Y-821327D02*
X98500Y-819962D01*
G01X104643Y-813872D02*
Y-820172D01*
G01X102841Y-813872D02*
X106445D01*
G01X108985Y-820172D02*
X110943Y-813872D01*
X112901Y-820172D01*
G01X112196Y-817967D02*
X109690D01*
G01X117243Y-820172D02*
X116616Y-820067D01*
X116068Y-819647D01*
X115598Y-819017D01*
X115285Y-818282D01*
X115128Y-817442D01*
Y-816602D01*
X115285Y-815762D01*
X115598Y-815027D01*
X116068Y-814397D01*
X116616Y-813977D01*
X117243Y-813872D01*
X117870Y-813977D01*
X118418Y-814397D01*
X118888Y-815027D01*
X119201Y-815762D01*
X119358Y-816602D01*
Y-817442D01*
X119201Y-818282D01*
X118888Y-819017D01*
X118418Y-819647D01*
X117870Y-820067D01*
X117243Y-820172D01*
G01X123543D02*
Y-817337D01*
X121976Y-813872D01*
G01X125110D02*
X123543Y-817337D01*
G01X128120Y-813872D02*
Y-818387D01*
X128433Y-819332D01*
X129060Y-819962D01*
X129843Y-820172D01*
X130626Y-819962D01*
X131253Y-819332D01*
X131566Y-818387D01*
Y-813872D01*
G01X134185Y-820172D02*
X136143Y-813872D01*
X138101Y-820172D01*
G01X137396Y-817967D02*
X134890D01*
G01X140641Y-820172D02*
Y-813872D01*
X144245Y-820172D01*
Y-813872D01*
G01X18166Y-824397D02*
X17696Y-824082D01*
X17148Y-823872D01*
X16521D01*
X15816Y-824187D01*
X15268Y-824712D01*
X14876Y-825342D01*
X14563Y-826392D01*
X14485Y-827337D01*
X14641Y-828282D01*
X14876Y-828912D01*
X15346Y-829542D01*
X15895Y-829962D01*
X16443Y-830172D01*
X16991D01*
X17540Y-829962D01*
X18010Y-829647D01*
X18401Y-829227D01*
G01X21803Y-823872D02*
X23683D01*
G01X22743D02*
Y-830172D01*
G01X21803D02*
X23683D01*
G01X29043Y-823872D02*
Y-830172D01*
G01X27241Y-823872D02*
X30845D01*
G01X35343Y-830172D02*
Y-827337D01*
X33776Y-823872D01*
G01X36910D02*
X35343Y-827337D01*
G01X46220Y-828912D02*
X46690Y-829647D01*
X47316Y-830067D01*
X48021Y-830172D01*
X48648Y-830067D01*
X49275Y-829542D01*
X49666Y-828912D01*
X49745Y-828282D01*
X49588Y-827547D01*
X49040Y-827022D01*
X48491Y-826812D01*
X47786D01*
G01X48491D02*
X48961Y-826497D01*
X49353Y-825972D01*
X49510Y-825342D01*
X49353Y-824712D01*
X48961Y-824187D01*
X48256Y-823872D01*
X47551Y-823977D01*
X46846Y-824397D01*
G01X52520Y-828912D02*
X52990Y-829647D01*
X53616Y-830067D01*
X54321Y-830172D01*
X54948Y-830067D01*
X55575Y-829542D01*
X55966Y-828912D01*
X56045Y-828282D01*
X55888Y-827547D01*
X55340Y-827022D01*
X54791Y-826812D01*
X54086D01*
G01X54791D02*
X55261Y-826497D01*
X55653Y-825972D01*
X55810Y-825342D01*
X55653Y-824712D01*
X55261Y-824187D01*
X54556Y-823872D01*
X53851Y-823977D01*
X53146Y-824397D01*
G01X58820Y-828912D02*
X59290Y-829647D01*
X59916Y-830067D01*
X60621Y-830172D01*
X61248Y-830067D01*
X61875Y-829542D01*
X62266Y-828912D01*
X62345Y-828282D01*
X62188Y-827547D01*
X61640Y-827022D01*
X61091Y-826812D01*
X60386D01*
G01X61091D02*
X61561Y-826497D01*
X61953Y-825972D01*
X62110Y-825342D01*
X61953Y-824712D01*
X61561Y-824187D01*
X60856Y-823872D01*
X60151Y-823977D01*
X59446Y-824397D01*
G01X66686Y-830172D02*
X66843Y-828807D01*
X67078Y-827652D01*
X67391Y-826602D01*
X67783Y-825447D01*
X68410Y-823872D01*
X65276D01*
G01X72986Y-830172D02*
X73143Y-828807D01*
X73378Y-827652D01*
X73691Y-826602D01*
X74083Y-825447D01*
X74710Y-823872D01*
X71576D01*
G01X79286Y-831327D02*
X79600Y-829962D01*
G01X85743Y-823872D02*
Y-830172D01*
G01X83941Y-823872D02*
X87545D01*
G01X90085Y-830172D02*
X92043Y-823872D01*
X94001Y-830172D01*
G01X93296Y-827967D02*
X90790D01*
G01X97403Y-823872D02*
X99283D01*
G01X98343D02*
Y-830172D01*
G01X97403D02*
X99283D01*
G01X102293Y-823872D02*
X103390Y-830172D01*
X104643Y-823872D01*
X105896Y-830172D01*
X106993Y-823872D01*
G01X108985Y-830172D02*
X110943Y-823872D01*
X112901Y-830172D01*
G01X112196Y-827967D02*
X109690D01*
G01X115441Y-830172D02*
Y-823872D01*
X119045Y-830172D01*
Y-823872D01*
G01X129451Y-832272D02*
X128668Y-831222D01*
X128276Y-830172D01*
Y-825972D01*
X128668Y-824922D01*
X129451Y-823872D01*
G01X140876Y-830172D02*
Y-823872D01*
X142835D01*
X143461Y-824187D01*
X143853Y-824607D01*
X144010Y-825447D01*
X143853Y-826287D01*
X143383Y-826812D01*
X142835Y-827127D01*
X140876D01*
G01X142835D02*
X144010Y-830172D01*
G01X148743Y-830382D02*
X148586Y-830277D01*
Y-830067D01*
X148743Y-829962D01*
X148900Y-830067D01*
Y-830277D01*
X148743Y-830382D01*
G01X155043Y-830172D02*
X154416Y-830067D01*
X153868Y-829647D01*
X153398Y-829017D01*
X153085Y-828282D01*
X152928Y-827442D01*
Y-826602D01*
X153085Y-825762D01*
X153398Y-825027D01*
X153868Y-824397D01*
X154416Y-823977D01*
X155043Y-823872D01*
X155670Y-823977D01*
X156218Y-824397D01*
X156688Y-825027D01*
X157001Y-825762D01*
X157158Y-826602D01*
Y-827442D01*
X157001Y-828282D01*
X156688Y-829017D01*
X156218Y-829647D01*
X155670Y-830067D01*
X155043Y-830172D01*
G01X161343Y-830382D02*
X161186Y-830277D01*
Y-830067D01*
X161343Y-829962D01*
X161500Y-830067D01*
Y-830277D01*
X161343Y-830382D01*
G01X169366Y-824397D02*
X168896Y-824082D01*
X168348Y-823872D01*
X167721D01*
X167016Y-824187D01*
X166468Y-824712D01*
X166076Y-825342D01*
X165763Y-826392D01*
X165685Y-827337D01*
X165841Y-828282D01*
X166076Y-828912D01*
X166546Y-829542D01*
X167095Y-829962D01*
X167643Y-830172D01*
X168191D01*
X168740Y-829962D01*
X169210Y-829647D01*
X169601Y-829227D01*
G01X173943Y-830382D02*
X173786Y-830277D01*
Y-830067D01*
X173943Y-829962D01*
X174100Y-830067D01*
Y-830277D01*
X173943Y-830382D01*
G01X180635Y-832272D02*
X181418Y-831222D01*
X181810Y-830172D01*
Y-825972D01*
X181418Y-824922D01*
X180635Y-823872D01*
G01X38743Y-799472D02*
X36223Y-799055D01*
X34018Y-797389D01*
X32128Y-794889D01*
X30868Y-791972D01*
X30238Y-788639D01*
Y-785305D01*
X30868Y-781972D01*
X32128Y-779055D01*
X34018Y-776556D01*
X36223Y-774889D01*
X38743Y-774472D01*
X41263Y-774889D01*
X43468Y-776556D01*
X45358Y-779055D01*
X46618Y-781972D01*
X47248Y-785305D01*
Y-788639D01*
X46618Y-791972D01*
X45358Y-794889D01*
X43468Y-797389D01*
X41263Y-799055D01*
X38743Y-799472D01*
G01X41263Y-792805D02*
X45043Y-799472D01*
G01X58588Y-782806D02*
Y-794472D01*
X59848Y-797389D01*
X61738Y-799055D01*
X63943Y-799472D01*
X66148Y-799055D01*
X68038Y-797389D01*
X69298Y-794472D01*
G01Y-799472D02*
Y-782806D01*
G01X94813Y-799472D02*
Y-782806D01*
G01Y-785722D02*
X93553Y-784056D01*
X91663Y-783222D01*
X89458Y-782806D01*
X87253Y-783639D01*
X85363Y-785305D01*
X84103Y-787806D01*
X83473Y-791139D01*
X84103Y-794472D01*
X85363Y-796973D01*
X87253Y-798639D01*
X89458Y-799472D01*
X91663Y-799055D01*
X93553Y-797806D01*
X94813Y-796139D01*
G01X108988Y-799472D02*
Y-782806D01*
G01Y-786972D02*
X110248Y-784889D01*
X112138Y-783222D01*
X114658Y-782806D01*
X116863Y-783222D01*
X118753Y-784889D01*
X119698Y-787806D01*
Y-799472D01*
G01X139543Y-774472D02*
Y-799472D01*
G01X135133Y-782806D02*
X143953D01*
G01X170413Y-799472D02*
Y-782806D01*
G01Y-785722D02*
X169153Y-784056D01*
X167263Y-783222D01*
X165058Y-782806D01*
X162853Y-783639D01*
X160963Y-785305D01*
X159703Y-787806D01*
X159073Y-791139D01*
X159703Y-794472D01*
X160963Y-796973D01*
X162853Y-798639D01*
X165058Y-799472D01*
X167263Y-799055D01*
X169153Y-797806D01*
X170413Y-796139D01*
G01X14641Y-810172D02*
Y-803872D01*
X18245Y-810172D01*
Y-803872D01*
G01X22743Y-810172D02*
X22116Y-810067D01*
X21568Y-809647D01*
X21098Y-809017D01*
X20785Y-808282D01*
X20628Y-807442D01*
Y-806602D01*
X20785Y-805762D01*
X21098Y-805027D01*
X21568Y-804397D01*
X22116Y-803977D01*
X22743Y-803872D01*
X23370Y-803977D01*
X23918Y-804397D01*
X24388Y-805027D01*
X24701Y-805762D01*
X24858Y-806602D01*
Y-807442D01*
X24701Y-808282D01*
X24388Y-809017D01*
X23918Y-809647D01*
X23370Y-810067D01*
X22743Y-810172D01*
G01X29043Y-810382D02*
X28886Y-810277D01*
Y-810067D01*
X29043Y-809962D01*
X29200Y-810067D01*
Y-810277D01*
X29043Y-810382D01*
G01X33855Y-804922D02*
X34325Y-804292D01*
X34873Y-803977D01*
X35500Y-803872D01*
X36283Y-804082D01*
X36831Y-804607D01*
X36988Y-805237D01*
X36910Y-805867D01*
X36596Y-806392D01*
X35030Y-807442D01*
X34325Y-808177D01*
X33855Y-809227D01*
X33698Y-810172D01*
X36988D01*
G01X41643D02*
Y-803872D01*
X40703Y-805132D01*
G01Y-810172D02*
X42583D01*
G01X47943D02*
Y-803872D01*
X47003Y-805132D01*
G01Y-810172D02*
X48883D01*
G01X54086Y-811327D02*
X54400Y-809962D01*
G01X58193Y-803872D02*
X59290Y-810172D01*
X60543Y-803872D01*
X61796Y-810172D01*
X62893Y-803872D01*
G01X68410Y-810172D02*
X65276D01*
Y-803872D01*
X68410D01*
G01X67156Y-806917D02*
X65276D01*
G01X71341Y-810172D02*
Y-803872D01*
X74945Y-810172D01*
Y-803872D01*
G01X77798Y-810172D02*
Y-803872D01*
G01X81088D02*
Y-810172D01*
G01Y-807022D02*
X77798D01*
G01X84020Y-803872D02*
Y-808387D01*
X84333Y-809332D01*
X84960Y-809962D01*
X85743Y-810172D01*
X86526Y-809962D01*
X87153Y-809332D01*
X87466Y-808387D01*
Y-803872D01*
G01X90085Y-810172D02*
X92043Y-803872D01*
X94001Y-810172D01*
G01X93296Y-807967D02*
X90790D01*
G01X103155Y-804922D02*
X103625Y-804292D01*
X104173Y-803977D01*
X104800Y-803872D01*
X105583Y-804082D01*
X106131Y-804607D01*
X106288Y-805237D01*
X106210Y-805867D01*
X105896Y-806392D01*
X104330Y-807442D01*
X103625Y-808177D01*
X103155Y-809227D01*
X102998Y-810172D01*
X106288D01*
G01X109141D02*
Y-803872D01*
X112745Y-810172D01*
Y-803872D01*
G01X115520Y-810172D02*
Y-803872D01*
X117086D01*
X117713Y-804187D01*
X118183Y-804607D01*
X118575Y-805237D01*
X118888Y-805972D01*
X118966Y-807022D01*
X118888Y-808072D01*
X118575Y-808807D01*
X118183Y-809437D01*
X117713Y-809857D01*
X117086Y-810172D01*
X115520D01*
G01X128276D02*
Y-803872D01*
X130235D01*
X130861Y-804187D01*
X131253Y-804607D01*
X131410Y-805447D01*
X131253Y-806287D01*
X130783Y-806812D01*
X130235Y-807127D01*
X128276D01*
G01X130235D02*
X131410Y-810172D01*
G01X134420D02*
Y-803872D01*
X135986D01*
X136613Y-804187D01*
X137083Y-804607D01*
X137475Y-805237D01*
X137788Y-805972D01*
X137866Y-807022D01*
X137788Y-808072D01*
X137475Y-808807D01*
X137083Y-809437D01*
X136613Y-809857D01*
X135986Y-810172D01*
X134420D01*
G01X142443Y-810382D02*
X142286Y-810277D01*
Y-810067D01*
X142443Y-809962D01*
X142600Y-810067D01*
Y-810277D01*
X142443Y-810382D01*
G01X210093Y-779172D02*
Y-787172D01*
X214093D01*
G01X221893D02*
Y-781839D01*
G01Y-782772D02*
X221493Y-782239D01*
X220893Y-781972D01*
X220193Y-781839D01*
X219493Y-782105D01*
X218893Y-782639D01*
X218493Y-783439D01*
X218293Y-784505D01*
X218493Y-785572D01*
X218893Y-786372D01*
X219493Y-786905D01*
X220193Y-787172D01*
X220893Y-787039D01*
X221493Y-786639D01*
X221893Y-786106D01*
G01X225993Y-789572D02*
X226593Y-789839D01*
X227393Y-789572D01*
X227893Y-789039D01*
X228293Y-788372D01*
X228893Y-786239D01*
X230193Y-781839D01*
G01X226993D02*
X228893Y-786239D01*
G01X234593Y-783572D02*
X237793D01*
X237493Y-782639D01*
X236993Y-782105D01*
X236293Y-781839D01*
X235593Y-781972D01*
X234993Y-782372D01*
X234593Y-783305D01*
X234393Y-784106D01*
Y-784905D01*
X234593Y-785705D01*
X235093Y-786505D01*
X235693Y-787039D01*
X236393Y-787172D01*
X237093Y-786905D01*
X237793Y-786106D01*
G01X242693Y-787172D02*
Y-781839D01*
G01Y-782905D02*
X243193Y-782372D01*
X243693Y-781972D01*
X244393Y-781839D01*
X244893Y-781972D01*
X245493Y-782372D01*
G01X229193Y-829172D02*
X232993D01*
X229193Y-837172D01*
X232993D01*
G01X239093Y-831839D02*
Y-837172D01*
G01Y-829705D02*
X238893Y-829572D01*
Y-829305D01*
X239093Y-829172D01*
X239293Y-829305D01*
Y-829572D01*
X239093Y-829705D01*
G01X245793Y-834505D02*
X248393D01*
G01X253093Y-837172D02*
Y-829172D01*
X255493D01*
X256293Y-829572D01*
X256893Y-830505D01*
X257093Y-831572D01*
X256893Y-832639D01*
X256393Y-833439D01*
X255493Y-833839D01*
X253093D01*
G01X263093Y-831839D02*
Y-837172D01*
G01Y-829705D02*
X262893Y-829572D01*
Y-829305D01*
X263093Y-829172D01*
X263293Y-829305D01*
Y-829572D01*
X263093Y-829705D01*
G01X269393Y-837172D02*
Y-831839D01*
G01Y-833172D02*
X269793Y-832505D01*
X270393Y-831972D01*
X271193Y-831839D01*
X271893Y-831972D01*
X272493Y-832505D01*
X272793Y-833439D01*
Y-837172D01*
G01X277693Y-839172D02*
X278393Y-839705D01*
X279193Y-839839D01*
X279893Y-839705D01*
X280493Y-839039D01*
X280893Y-838105D01*
Y-831839D01*
G01Y-832905D02*
X280493Y-832372D01*
X279893Y-831972D01*
X279193Y-831839D01*
X278393Y-832105D01*
X277893Y-832639D01*
X277493Y-833572D01*
X277293Y-834505D01*
X277393Y-835305D01*
X277793Y-836239D01*
X278393Y-836905D01*
X279193Y-837172D01*
X279793Y-837039D01*
X280493Y-836505D01*
X280893Y-835972D01*
G01X241093Y-804172D02*
X243593Y-812172D01*
X246093Y-804172D01*
G01X253793Y-804839D02*
X253193Y-804439D01*
X252493Y-804172D01*
X251693D01*
X250793Y-804572D01*
X250093Y-805239D01*
X249593Y-806039D01*
X249193Y-807372D01*
X249093Y-808572D01*
X249293Y-809772D01*
X249593Y-810572D01*
X250193Y-811372D01*
X250893Y-811905D01*
X251593Y-812172D01*
X252293D01*
X252993Y-811905D01*
X253593Y-811505D01*
X254093Y-810972D01*
G01X261793Y-804839D02*
X261193Y-804439D01*
X260493Y-804172D01*
X259693D01*
X258793Y-804572D01*
X258093Y-805239D01*
X257593Y-806039D01*
X257193Y-807372D01*
X257093Y-808572D01*
X257293Y-809772D01*
X257593Y-810572D01*
X258193Y-811372D01*
X258893Y-811905D01*
X259593Y-812172D01*
X260293D01*
X260993Y-811905D01*
X261593Y-811505D01*
X262093Y-810972D01*
G01X267593Y-812172D02*
Y-804172D01*
X266393Y-805772D01*
G01Y-812172D02*
X268793D01*
G01X261693Y-783839D02*
X262393Y-782905D01*
X262993Y-782372D01*
X263793Y-782105D01*
X264493Y-782372D01*
X264993Y-782905D01*
X265393Y-783705D01*
X265493Y-784639D01*
X265393Y-785439D01*
X264993Y-786239D01*
X264393Y-786905D01*
X263693Y-787172D01*
X262893Y-786905D01*
X262193Y-786106D01*
X261793Y-784905D01*
X261693Y-783572D01*
X261893Y-781839D01*
X262193Y-780905D01*
X262693Y-779972D01*
X263393Y-779305D01*
X264093Y-779172D01*
X264793Y-779439D01*
X265293Y-780105D01*
G01X336693Y-830505D02*
X337293Y-829705D01*
X337993Y-829305D01*
X338793Y-829172D01*
X339793Y-829439D01*
X340493Y-830105D01*
X340693Y-830905D01*
X340593Y-831706D01*
X340193Y-832372D01*
X338193Y-833705D01*
X337293Y-834639D01*
X336693Y-835972D01*
X336493Y-837172D01*
X340693D01*
G01X346593Y-829172D02*
X345793Y-829439D01*
X345193Y-830105D01*
X344793Y-830905D01*
X344493Y-831972D01*
X344393Y-833172D01*
X344493Y-834372D01*
X344793Y-835439D01*
X345193Y-836239D01*
X345793Y-836905D01*
X346593Y-837172D01*
X347393Y-836905D01*
X347993Y-836239D01*
X348393Y-835439D01*
X348693Y-834372D01*
X348793Y-833172D01*
X348693Y-831972D01*
X348393Y-830905D01*
X347993Y-830105D01*
X347393Y-829439D01*
X346593Y-829172D01*
G01X352693Y-830505D02*
X353293Y-829705D01*
X353993Y-829305D01*
X354793Y-829172D01*
X355793Y-829439D01*
X356493Y-830105D01*
X356693Y-830905D01*
X356593Y-831706D01*
X356193Y-832372D01*
X354193Y-833705D01*
X353293Y-834639D01*
X352693Y-835972D01*
X352493Y-837172D01*
X356693D01*
G01X360693Y-830505D02*
X361293Y-829705D01*
X361993Y-829305D01*
X362793Y-829172D01*
X363793Y-829439D01*
X364493Y-830105D01*
X364693Y-830905D01*
X364593Y-831706D01*
X364193Y-832372D01*
X362193Y-833705D01*
X361293Y-834639D01*
X360693Y-835972D01*
X360493Y-837172D01*
X364693D01*
G01X368793Y-837439D02*
X372393Y-829172D01*
G01X378593Y-837172D02*
Y-829172D01*
X377393Y-830772D01*
G01Y-837172D02*
X379793D01*
G01X384693Y-830505D02*
X385293Y-829705D01*
X385993Y-829305D01*
X386793Y-829172D01*
X387793Y-829439D01*
X388493Y-830105D01*
X388693Y-830905D01*
X388593Y-831706D01*
X388193Y-832372D01*
X386193Y-833705D01*
X385293Y-834639D01*
X384693Y-835972D01*
X384493Y-837172D01*
X388693D01*
G01X392793Y-837439D02*
X396393Y-829172D01*
G01X402593D02*
X401793Y-829439D01*
X401193Y-830105D01*
X400793Y-830905D01*
X400493Y-831972D01*
X400393Y-833172D01*
X400493Y-834372D01*
X400793Y-835439D01*
X401193Y-836239D01*
X401793Y-836905D01*
X402593Y-837172D01*
X403393Y-836905D01*
X403993Y-836239D01*
X404393Y-835439D01*
X404693Y-834372D01*
X404793Y-833172D01*
X404693Y-831972D01*
X404393Y-830905D01*
X403993Y-830105D01*
X403393Y-829439D01*
X402593Y-829172D01*
G01X408693Y-830505D02*
X409293Y-829705D01*
X409993Y-829305D01*
X410793Y-829172D01*
X411793Y-829439D01*
X412493Y-830105D01*
X412693Y-830905D01*
X412593Y-831706D01*
X412193Y-832372D01*
X410193Y-833705D01*
X409293Y-834639D01*
X408693Y-835972D01*
X408493Y-837172D01*
X412693D01*
G01X336393Y-814672D02*
Y-806672D01*
X338393D01*
X339193Y-807072D01*
X339793Y-807605D01*
X340293Y-808405D01*
X340693Y-809339D01*
X340793Y-810672D01*
X340693Y-812005D01*
X340293Y-812939D01*
X339793Y-813739D01*
X339193Y-814272D01*
X338393Y-814672D01*
X336393D01*
G01X344093D02*
X346593Y-806672D01*
X349093Y-814672D01*
G01X348193Y-811872D02*
X344993D01*
G01X354593Y-806672D02*
X353793Y-806939D01*
X353193Y-807605D01*
X352793Y-808405D01*
X352493Y-809472D01*
X352393Y-810672D01*
X352493Y-811872D01*
X352793Y-812939D01*
X353193Y-813739D01*
X353793Y-814405D01*
X354593Y-814672D01*
X355393Y-814405D01*
X355993Y-813739D01*
X356393Y-812939D01*
X356693Y-811872D01*
X356793Y-810672D01*
X356693Y-809472D01*
X356393Y-808405D01*
X355993Y-807605D01*
X355393Y-806939D01*
X354593Y-806672D01*
G01X360693Y-814672D02*
Y-806672D01*
X364493D01*
G01X363093Y-810539D02*
X360693D01*
G01X370593Y-806672D02*
X369793Y-806939D01*
X369193Y-807605D01*
X368793Y-808405D01*
X368493Y-809472D01*
X368393Y-810672D01*
X368493Y-811872D01*
X368793Y-812939D01*
X369193Y-813739D01*
X369793Y-814405D01*
X370593Y-814672D01*
X371393Y-814405D01*
X371993Y-813739D01*
X372393Y-812939D01*
X372693Y-811872D01*
X372793Y-810672D01*
X372693Y-809472D01*
X372393Y-808405D01*
X371993Y-807605D01*
X371393Y-806939D01*
X370593Y-806672D01*
G01X378593D02*
Y-814672D01*
G01X376293Y-806672D02*
X380893D01*
G01X384593Y-814672D02*
Y-806672D01*
X386993D01*
X387793Y-807072D01*
X388393Y-808005D01*
X388593Y-809072D01*
X388393Y-810139D01*
X387893Y-810939D01*
X386993Y-811339D01*
X384593D01*
G01X395393Y-810405D02*
X395793Y-810005D01*
X396093Y-809339D01*
X396293Y-808405D01*
X396093Y-807605D01*
X395693Y-807072D01*
X394993Y-806672D01*
X392293D01*
Y-814672D01*
X395593D01*
X396293Y-814139D01*
X396693Y-813339D01*
X396893Y-812405D01*
X396693Y-811472D01*
X396093Y-810672D01*
X395393Y-810405D01*
X392293D01*
G01X400093Y-814672D02*
X402593Y-806672D01*
X405093Y-814672D01*
G01X404193Y-811872D02*
X400993D01*
G01X408693Y-814672D02*
Y-806672D01*
X412493D01*
G01X411093Y-810539D02*
X408693D01*
G01X418593Y-806672D02*
X417793Y-806939D01*
X417193Y-807605D01*
X416793Y-808405D01*
X416493Y-809472D01*
X416393Y-810672D01*
X416493Y-811872D01*
X416793Y-812939D01*
X417193Y-813739D01*
X417793Y-814405D01*
X418593Y-814672D01*
X419393Y-814405D01*
X419993Y-813739D01*
X420393Y-812939D01*
X420693Y-811872D01*
X420793Y-810672D01*
X420693Y-809472D01*
X420393Y-808405D01*
X419993Y-807605D01*
X419393Y-806939D01*
X418593Y-806672D01*
G01X356693Y-787172D02*
Y-779172D01*
X360493D01*
G01X359093Y-783039D02*
X356693D01*
G01X366593Y-779172D02*
X365793Y-779439D01*
X365193Y-780105D01*
X364793Y-780905D01*
X364493Y-781972D01*
X364393Y-783172D01*
X364493Y-784372D01*
X364793Y-785439D01*
X365193Y-786239D01*
X365793Y-786905D01*
X366593Y-787172D01*
X367393Y-786905D01*
X367993Y-786239D01*
X368393Y-785439D01*
X368693Y-784372D01*
X368793Y-783172D01*
X368693Y-781972D01*
X368393Y-780905D01*
X367993Y-780105D01*
X367393Y-779439D01*
X366593Y-779172D01*
G01X374593D02*
Y-787172D01*
G01X372293Y-779172D02*
X376893D01*
G01X379593Y-789839D02*
X385593D01*
G01X388593Y-787172D02*
Y-779172D01*
X390993D01*
X391793Y-779572D01*
X392393Y-780505D01*
X392593Y-781572D01*
X392393Y-782639D01*
X391893Y-783439D01*
X390993Y-783839D01*
X388593D01*
G01X396393Y-787172D02*
Y-779172D01*
X398393D01*
X399193Y-779572D01*
X399793Y-780105D01*
X400293Y-780905D01*
X400693Y-781839D01*
X400793Y-783172D01*
X400693Y-784505D01*
X400293Y-785439D01*
X399793Y-786239D01*
X399193Y-786772D01*
X398393Y-787172D01*
X396393D01*
G01X407393Y-782905D02*
X407793Y-782505D01*
X408093Y-781839D01*
X408293Y-780905D01*
X408093Y-780105D01*
X407693Y-779572D01*
X406993Y-779172D01*
X404293D01*
Y-787172D01*
X407593D01*
X408293Y-786639D01*
X408693Y-785839D01*
X408893Y-784905D01*
X408693Y-783972D01*
X408093Y-783172D01*
X407393Y-782905D01*
X404293D01*
G01X411593Y-789839D02*
X417593D01*
G01X424793Y-779839D02*
X424193Y-779439D01*
X423493Y-779172D01*
X422693D01*
X421793Y-779572D01*
X421093Y-780239D01*
X420593Y-781039D01*
X420193Y-782372D01*
X420093Y-783572D01*
X420293Y-784772D01*
X420593Y-785572D01*
X421193Y-786372D01*
X421893Y-786905D01*
X422593Y-787172D01*
X423293D01*
X423993Y-786905D01*
X424593Y-786505D01*
X425093Y-785972D01*
G01X430593Y-787172D02*
X429793Y-787039D01*
X429093Y-786505D01*
X428493Y-785705D01*
X428093Y-784772D01*
X427893Y-783705D01*
Y-782639D01*
X428093Y-781572D01*
X428493Y-780639D01*
X429093Y-779839D01*
X429793Y-779305D01*
X430593Y-779172D01*
X431393Y-779305D01*
X432093Y-779839D01*
X432693Y-780639D01*
X433093Y-781572D01*
X433293Y-782639D01*
Y-783705D01*
X433093Y-784772D01*
X432693Y-785705D01*
X432093Y-786505D01*
X431393Y-787039D01*
X430593Y-787172D01*
G01X436293D02*
Y-779172D01*
X440893Y-787172D01*
Y-779172D01*
G01X444093D02*
X446593Y-787172D01*
X449093Y-779172D01*
G01X456593Y-787172D02*
X452593D01*
Y-779172D01*
X456593D01*
G01X454993Y-783039D02*
X452593D01*
G01X460593Y-787172D02*
Y-779172D01*
X463093D01*
X463893Y-779572D01*
X464393Y-780105D01*
X464593Y-781172D01*
X464393Y-782239D01*
X463793Y-782905D01*
X463093Y-783305D01*
X460593D01*
G01X463093D02*
X464593Y-787172D01*
G01X470593Y-779172D02*
Y-787172D01*
G01X468293Y-779172D02*
X472893D01*
G01X480593Y-787172D02*
X476593D01*
Y-779172D01*
X480593D01*
G01X478993Y-783039D02*
X476593D01*
G01X484593Y-787172D02*
Y-779172D01*
X487093D01*
X487893Y-779572D01*
X488393Y-780105D01*
X488593Y-781172D01*
X488393Y-782239D01*
X487793Y-782905D01*
X487093Y-783305D01*
X484593D01*
G01X487093D02*
X488593Y-787172D01*
G01X425093Y-840172D02*
Y-832172D01*
X423893Y-833772D01*
G01Y-840172D02*
X426293D01*
G01X431193Y-836839D02*
X431893Y-835905D01*
X432493Y-835372D01*
X433293Y-835105D01*
X433993Y-835372D01*
X434493Y-835905D01*
X434893Y-836705D01*
X434993Y-837639D01*
X434893Y-838439D01*
X434493Y-839239D01*
X433893Y-839905D01*
X433193Y-840172D01*
X432393Y-839905D01*
X431693Y-839106D01*
X431293Y-837905D01*
X431193Y-836572D01*
X431393Y-834839D01*
X431693Y-833905D01*
X432193Y-832972D01*
X432893Y-832305D01*
X433593Y-832172D01*
X434293Y-832439D01*
X434793Y-833105D01*
G01X441093Y-840439D02*
X440893Y-840305D01*
Y-840039D01*
X441093Y-839905D01*
X441293Y-840039D01*
Y-840305D01*
X441093Y-840439D01*
G01X447193Y-836839D02*
X447893Y-835905D01*
X448493Y-835372D01*
X449293Y-835105D01*
X449993Y-835372D01*
X450493Y-835905D01*
X450893Y-836705D01*
X450993Y-837639D01*
X450893Y-838439D01*
X450493Y-839239D01*
X449893Y-839905D01*
X449193Y-840172D01*
X448393Y-839905D01*
X447693Y-839106D01*
X447293Y-837905D01*
X447193Y-836572D01*
X447393Y-834839D01*
X447693Y-833905D01*
X448193Y-832972D01*
X448893Y-832305D01*
X449593Y-832172D01*
X450293Y-832439D01*
X450793Y-833105D01*
G01X470093Y-840172D02*
Y-832172D01*
X468893Y-833772D01*
G01Y-840172D02*
X471293D01*
G01X477893D02*
X478093Y-838439D01*
X478393Y-836972D01*
X478793Y-835639D01*
X479293Y-834172D01*
X480093Y-832172D01*
X476093D01*
G01X486093Y-840439D02*
X485893Y-840305D01*
Y-840039D01*
X486093Y-839905D01*
X486293Y-840039D01*
Y-840305D01*
X486093Y-840439D01*
G01X492193Y-833505D02*
X492793Y-832705D01*
X493493Y-832305D01*
X494293Y-832172D01*
X495293Y-832439D01*
X495993Y-833105D01*
X496193Y-833905D01*
X496093Y-834706D01*
X495693Y-835372D01*
X493693Y-836705D01*
X492793Y-837639D01*
X492193Y-838972D01*
X491993Y-840172D01*
X496193D01*
G01X490193Y-815172D02*
Y-807172D01*
X493993D01*
G01X492593Y-811039D02*
X490193D01*
M02*
